FILE_TYPE = MACRO_DRAWING;
SET COLOR_WIRE YELLOW;
SET COLOR_PROP ORANGE;
SET COLOR_DOT WHITE;
SET COLOR_ARC YELLOW;
SET COLOR_BODY GREEN;
SET COLOR_NOTE PURPLE;
SET PROP_DISPLAY VALUE;
SET PAGE_NUMBER P430;
FORCEADD OFFPAGE..1
(-8050 1200);
FORCEPROP 2 LAST $XR0 182 
J 0
(-8332 1200);
DISPLAY 0.638298 (-8332 1200);
PAINT MONO (-8332 1200);
FORCEPROP 2 LAST CDS_LIB standard
J 0
(-8050 1200);
DISPLAY INVISIBLE (-8050 1200);
FORCEPROP 1 LAST OFFPAGE TRUE
J 0
(-7725 1075);
DISPLAY 0.872340 (-7725 1075);
DISPLAY INVISIBLE (-7725 1075);
FORCEPROP 1 LAST COMMENT_BODY TRUE
J 0
(-7925 1100);
DISPLAY 0.872340 (-7925 1100);
PAINT GREEN (-7925 1100);
DISPLAY INVISIBLE (-7925 1100);
FORCEPROP 2 LAST PATH I1
J 0
(-8325 1250);
DISPLAY 0.680851 (-8325 1250);
DISPLAY INVISIBLE (-8325 1250);
FORCEADD Q_RES..2
(-8950 6000);
FORCEPROP 1 LAST LOCATION R1111
J 0
(-8905 6125);
DISPLAY 0.787234 (-8905 6125);
FORCEPROP 0 LAST $SEC 1
J 0
(-8900 6175);
DISPLAY 0.680851 (-8900 6175);
PAINT MONO (-8900 6175);
DISPLAY INVISIBLE (-8900 6175);
FORCEPROP 0 LAST CDS_SEC 1
J 0
(-8900 6175);
DISPLAY 0.680851 (-8900 6175);
DISPLAY INVISIBLE (-8900 6175);
FORCEPROP 1 LASTPIN (-8950 6100) $PN 1
J 0
(-8945 6062);
DISPLAY 0.787234 (-8945 6062);
PAINT MONO (-8945 6062);
FORCEPROP 1 LASTPIN (-8950 5900) $PN 2
J 0
(-8945 5910);
DISPLAY 0.787234 (-8945 5910);
PAINT MONO (-8945 5910);
FORCEPROP 1 LAST TOLERANCE 5%
J 0
(-8905 6025);
DISPLAY 0.787234 (-8905 6025);
FORCEPROP 1 LAST VALUE 4.7K
J 0
(-8905 6075);
DISPLAY 0.787234 (-8905 6075);
FORCEPROP 1 LAST PACK_TYPE 0201LF
J 0
(-8900 5850);
DISPLAY 0.787234 (-8900 5850);
FORCEPROP 1 LAST MATERIAL EMPTY
J 0
(-8910 5925);
DISPLAY 0.787234 (-8910 5925);
FORCEPROP 1 LAST WATTAGE 1/20W
J 0
(-8910 5975);
DISPLAY 0.787234 (-8910 5975);
FORCEPROP 2 LAST CDS_LIB pure_quanta
J 0
(-8950 6000);
DISPLAY INVISIBLE (-8950 6000);
FORCEPROP 1 LAST PATH I10
J 0
(-8900 6175);
DISPLAY 0.978723 (-8900 6175);
PAINT WHITE (-8900 6175);
DISPLAY INVISIBLE (-8900 6175);
FORCEPROP 1 LAST PART_NUMBER CS24701JE04
J 0
(-8910 5875);
DISPLAY 0.978723 (-8910 5875);
DISPLAY INVISIBLE (-8910 5875);
FORCEADD UNIVERSAL_GND..1
R 1
(-1950 2300);
FORCEPROP 3 LASTPIN (-2000 2300) SIG_NAME GND\g
J 0
(-1990 2310);
DISPLAY 0.659574 (-1990 2310);
PAINT MONO (-1990 2310);
DISPLAY INVISIBLE (-1990 2310);
FORCEPROP 2 LAST CDS_LIB pure_quanta_power
J 0
(-1950 2300);
DISPLAY INVISIBLE (-1950 2300);
FORCEPROP 1 LAST HDL_POWER GND
R 1
J 1
(-1875 2325);
DISPLAY 0.872340 (-1875 2325);
PAINT GREEN (-1875 2325);
DISPLAY INVISIBLE (-1875 2325);
FORCEPROP 1 LAST PATH I100
R 1
J 0
(-1950 2375);
DISPLAY 0.872340 (-1950 2375);
PAINT AQUA (-1950 2375);
DISPLAY INVISIBLE (-1950 2375);
FORCEADD Q_RES..1
(-2675 2300);
FORCEPROP 1 LAST LOCATION R1412
J 0
(-2725 2350);
DISPLAY 0.978723 (-2725 2350);
FORCEPROP 0 LAST $SEC 1
J 0
(-2725 2400);
DISPLAY 0.680851 (-2725 2400);
PAINT MONO (-2725 2400);
DISPLAY INVISIBLE (-2725 2400);
FORCEPROP 0 LAST CDS_SEC 1
J 0
(-2725 2400);
DISPLAY 0.680851 (-2725 2400);
DISPLAY INVISIBLE (-2725 2400);
FORCEPROP 1 LASTPIN (-2775 2300) $PN 1
J 0
(-2763 2312);
DISPLAY 0.787234 (-2763 2312);
PAINT MONO (-2763 2312);
FORCEPROP 1 LASTPIN (-2575 2300) $PN 2
J 0
(-2613 2312);
DISPLAY 0.787234 (-2613 2312);
PAINT MONO (-2613 2312);
FORCEPROP 1 LAST VALUE 4.7K
J 2
(-2425 2300);
DISPLAY 0.638298 (-2425 2300);
FORCEPROP 1 LAST PACK_TYPE 0201LF
J 0
(-2250 2300);
DISPLAY 0.638298 (-2250 2300);
FORCEPROP 1 LAST MATERIAL CHIP
J 0
(-2400 2300);
DISPLAY 0.638298 (-2400 2300);
FORCEPROP 1 LAST WATTAGE 1/20W
J 2
(-2700 2150);
DISPLAY 0.978723 (-2700 2150);
DISPLAY INVISIBLE (-2700 2150);
FORCEPROP 1 LAST TOLERANCE 5%
J 0
(-2675 2200);
DISPLAY 0.978723 (-2675 2200);
DISPLAY INVISIBLE (-2675 2200);
FORCEPROP 2 LAST CDS_LIB pure_quanta
J 0
(-2675 2300);
DISPLAY INVISIBLE (-2675 2300);
FORCEPROP 1 LAST PATH I101
J 0
(-2725 2450);
DISPLAY 0.978723 (-2725 2450);
PAINT WHITE (-2725 2450);
DISPLAY INVISIBLE (-2725 2450);
FORCEPROP 1 LAST PART_NUMBER CS24701JE04
J 0
(-2725 2400);
DISPLAY 0.978723 (-2725 2400);
DISPLAY INVISIBLE (-2725 2400);
FORCEADD Q_RES..2
(-8975 3450);
FORCEPROP 1 LAST LOCATION R1106
J 0
(-8930 3575);
DISPLAY 0.978723 (-8930 3575);
PAINT WHITE (-8930 3575);
FORCEPROP 0 LAST $SEC 1
J 0
(-8925 3625);
DISPLAY 0.680851 (-8925 3625);
PAINT MONO (-8925 3625);
DISPLAY INVISIBLE (-8925 3625);
FORCEPROP 0 LAST CDS_SEC 1
J 0
(-8925 3625);
DISPLAY 0.680851 (-8925 3625);
DISPLAY INVISIBLE (-8925 3625);
FORCEPROP 1 LASTPIN (-8975 3550) $PN 1
J 0
(-8970 3512);
DISPLAY 0.787234 (-8970 3512);
PAINT MONO (-8970 3512);
FORCEPROP 1 LASTPIN (-8975 3350) $PN 2
J 0
(-8970 3360);
DISPLAY 0.787234 (-8970 3360);
PAINT MONO (-8970 3360);
FORCEPROP 1 LAST PACK_TYPE 0201LF
J 0
(-8935 3275);
DISPLAY 0.978723 (-8935 3275);
FORCEPROP 1 LAST MATERIAL CHIP
J 0
(-8935 3375);
DISPLAY 0.978723 (-8935 3375);
FORCEPROP 1 LAST WATTAGE 1/20W
J 0
(-8935 3425);
DISPLAY 0.978723 (-8935 3425);
FORCEPROP 1 LAST TOLERANCE 1%
J 0
(-8930 3475);
DISPLAY 0.978723 (-8930 3475);
FORCEPROP 1 LAST VALUE 200
J 0
(-8930 3525);
DISPLAY 0.978723 (-8930 3525);
FORCEPROP 2 LAST CDS_LIB pure_quanta
J 0
(-8975 3450);
DISPLAY INVISIBLE (-8975 3450);
FORCEPROP 1 LAST PATH I102
J 0
(-8925 3625);
DISPLAY 0.978723 (-8925 3625);
PAINT WHITE (-8925 3625);
DISPLAY INVISIBLE (-8925 3625);
FORCEPROP 1 LAST PART_NUMBER CS12001FE12
J 0
(-8935 3325);
DISPLAY 0.978723 (-8935 3325);
DISPLAY INVISIBLE (-8935 3325);
FORCEADD OFFPAGE..5
(-2400 1075);
FORCEPROP 2 LAST $XR0 310 
J 0
(-2655 1075);
DISPLAY 0.638298 (-2655 1075);
PAINT MONO (-2655 1075);
FORCEPROP 2 LAST CDS_LIB standard
J 0
(-2400 1075);
DISPLAY INVISIBLE (-2400 1075);
FORCEPROP 1 LAST OFFPAGE TRUE
J 0
(-2075 950);
DISPLAY 0.872340 (-2075 950);
PAINT GREEN (-2075 950);
DISPLAY INVISIBLE (-2075 950);
FORCEPROP 1 LAST COMMENT_BODY TRUE
J 0
(-2300 1000);
DISPLAY 0.872340 (-2300 1000);
PAINT GREEN (-2300 1000);
DISPLAY INVISIBLE (-2300 1000);
FORCEPROP 2 LAST PATH I103
J 0
(-2350 1150);
DISPLAY 0.680851 (-2350 1150);
DISPLAY INVISIBLE (-2350 1150);
FORCEADD OFFPAGE..5
(-2400 1125);
FORCEPROP 2 LAST $XR0 310 
J 0
(-2655 1125);
DISPLAY 0.638298 (-2655 1125);
PAINT MONO (-2655 1125);
FORCEPROP 2 LAST CDS_LIB standard
J 2
(-2400 1125);
DISPLAY INVISIBLE (-2400 1125);
FORCEPROP 1 LAST OFFPAGE TRUE
J 0
(-2075 1000);
DISPLAY 0.872340 (-2075 1000);
PAINT GREEN (-2075 1000);
DISPLAY INVISIBLE (-2075 1000);
FORCEPROP 1 LAST COMMENT_BODY TRUE
J 0
(-2300 1050);
DISPLAY 0.872340 (-2300 1050);
PAINT GREEN (-2300 1050);
DISPLAY INVISIBLE (-2300 1050);
FORCEPROP 2 LAST PATH I104
J 0
(-2350 1200);
DISPLAY 0.680851 (-2350 1200);
DISPLAY INVISIBLE (-2350 1200);
FORCEADD Q_RES..2
(-8325 6000);
FORCEPROP 1 LAST LOCATION R1114
J 0
(-8280 6125);
DISPLAY 0.787234 (-8280 6125);
FORCEPROP 0 LAST $SEC 1
J 0
(-8275 6175);
DISPLAY 0.680851 (-8275 6175);
PAINT MONO (-8275 6175);
DISPLAY INVISIBLE (-8275 6175);
FORCEPROP 0 LAST CDS_SEC 1
J 0
(-8275 6175);
DISPLAY 0.680851 (-8275 6175);
DISPLAY INVISIBLE (-8275 6175);
FORCEPROP 1 LASTPIN (-8325 6100) $PN 1
J 0
(-8320 6062);
DISPLAY 0.787234 (-8320 6062);
PAINT MONO (-8320 6062);
FORCEPROP 1 LASTPIN (-8325 5900) $PN 2
J 0
(-8320 5910);
DISPLAY 0.787234 (-8320 5910);
PAINT MONO (-8320 5910);
FORCEPROP 1 LAST MATERIAL EMPTY
J 0
(-8285 5925);
DISPLAY 0.787234 (-8285 5925);
FORCEPROP 1 LAST PACK_TYPE 0201LF
J 0
(-8275 5850);
DISPLAY 0.787234 (-8275 5850);
FORCEPROP 1 LAST WATTAGE 1/20W
J 0
(-8285 5975);
DISPLAY 0.787234 (-8285 5975);
FORCEPROP 1 LAST TOLERANCE 5%
J 0
(-8280 6025);
DISPLAY 0.787234 (-8280 6025);
FORCEPROP 1 LAST VALUE 4.7K
J 0
(-8280 6075);
DISPLAY 0.787234 (-8280 6075);
FORCEPROP 2 LAST CDS_LIB pure_quanta
J 0
(-8325 6000);
DISPLAY INVISIBLE (-8325 6000);
FORCEPROP 1 LAST PATH I11
J 0
(-8275 6175);
DISPLAY 0.978723 (-8275 6175);
PAINT WHITE (-8275 6175);
DISPLAY INVISIBLE (-8275 6175);
FORCEPROP 1 LAST PART_NUMBER CS24701JE04
J 0
(-8285 5875);
DISPLAY 0.978723 (-8285 5875);
DISPLAY INVISIBLE (-8285 5875);
FORCEADD Q_RES..2
(-1250 1375);
FORCEPROP 1 LAST LOCATION R1482
J 0
(-1205 1500);
DISPLAY 0.978723 (-1205 1500);
FORCEPROP 0 LAST $SEC 1
J 0
(-1200 1550);
DISPLAY 0.680851 (-1200 1550);
PAINT MONO (-1200 1550);
DISPLAY INVISIBLE (-1200 1550);
FORCEPROP 0 LAST CDS_SEC 1
J 0
(-1200 1550);
DISPLAY 0.680851 (-1200 1550);
DISPLAY INVISIBLE (-1200 1550);
FORCEPROP 1 LASTPIN (-1250 1475) $PN 1
J 0
(-1245 1437);
DISPLAY 0.787234 (-1245 1437);
PAINT MONO (-1245 1437);
FORCEPROP 1 LASTPIN (-1250 1275) $PN 2
J 0
(-1245 1285);
DISPLAY 0.787234 (-1245 1285);
PAINT MONO (-1245 1285);
FORCEPROP 1 LAST PACK_TYPE 0201LF
J 0
(-1200 1225);
DISPLAY 0.787234 (-1200 1225);
FORCEPROP 1 LAST MATERIAL EMPTY
J 0
(-1210 1300);
DISPLAY 0.787234 (-1210 1300);
PAINT RED (-1210 1300);
FORCEPROP 1 LAST WATTAGE 1/20W
J 0
(-1210 1350);
DISPLAY 0.787234 (-1210 1350);
FORCEPROP 1 LAST TOLERANCE 5%
J 0
(-1205 1400);
DISPLAY 0.787234 (-1205 1400);
FORCEPROP 1 LAST VALUE 4.7K
J 0
(-1205 1450);
DISPLAY 0.787234 (-1205 1450);
FORCEPROP 2 LAST CDS_LIB pure_quanta
J 0
(-1250 1375);
DISPLAY INVISIBLE (-1250 1375);
FORCEPROP 1 LAST PATH I112
J 0
(-1200 1550);
DISPLAY 0.978723 (-1200 1550);
PAINT WHITE (-1200 1550);
DISPLAY INVISIBLE (-1200 1550);
FORCEPROP 1 LAST PART_NUMBER CS24701JE04
J 0
(-1210 1250);
DISPLAY 0.978723 (-1210 1250);
DISPLAY INVISIBLE (-1210 1250);
FORCEADD Q_RES..2
(-975 1375);
FORCEPROP 1 LAST LOCATION R1483
J 0
(-930 1500);
DISPLAY 0.978723 (-930 1500);
FORCEPROP 0 LAST $SEC 1
J 0
(-925 1550);
DISPLAY 0.680851 (-925 1550);
PAINT MONO (-925 1550);
DISPLAY INVISIBLE (-925 1550);
FORCEPROP 0 LAST CDS_SEC 1
J 0
(-925 1550);
DISPLAY 0.680851 (-925 1550);
DISPLAY INVISIBLE (-925 1550);
FORCEPROP 1 LASTPIN (-975 1475) $PN 1
J 0
(-970 1437);
DISPLAY 0.787234 (-970 1437);
PAINT MONO (-970 1437);
FORCEPROP 1 LASTPIN (-975 1275) $PN 2
J 0
(-970 1285);
DISPLAY 0.787234 (-970 1285);
PAINT MONO (-970 1285);
FORCEPROP 1 LAST PACK_TYPE 0201LF
J 0
(-925 1225);
DISPLAY 0.787234 (-925 1225);
FORCEPROP 1 LAST VALUE 4.7K
J 0
(-930 1450);
DISPLAY 0.787234 (-930 1450);
FORCEPROP 1 LAST MATERIAL EMPTY
J 0
(-935 1300);
DISPLAY 0.787234 (-935 1300);
PAINT RED (-935 1300);
FORCEPROP 1 LAST TOLERANCE 5%
J 0
(-930 1400);
DISPLAY 0.787234 (-930 1400);
FORCEPROP 1 LAST WATTAGE 1/20W
J 0
(-935 1350);
DISPLAY 0.787234 (-935 1350);
FORCEPROP 2 LAST CDS_LIB pure_quanta
J 0
(-975 1375);
DISPLAY INVISIBLE (-975 1375);
FORCEPROP 1 LAST PATH I113
J 0
(-925 1550);
DISPLAY 0.978723 (-925 1550);
PAINT WHITE (-925 1550);
DISPLAY INVISIBLE (-925 1550);
FORCEPROP 1 LAST PART_NUMBER CS24701JE04
J 0
(-935 1250);
DISPLAY 0.978723 (-935 1250);
DISPLAY INVISIBLE (-935 1250);
FORCEADD GND..1
(-425 450);
FORCEPROP 3 LASTPIN (-425 500) SIG_NAME GND\g
J 0
(-415 510);
DISPLAY 0.659574 (-415 510);
PAINT MONO (-415 510);
DISPLAY INVISIBLE (-415 510);
FORCEPROP 1 LAST SIZE 1B
J 0
(-350 400);
DISPLAY 0.851064 (-350 400);
PAINT GREEN (-350 400);
DISPLAY INVISIBLE (-350 400);
FORCEPROP 2 LAST BOM_COST MEM
J 0
(-525 525);
DISPLAY 0.808511 (-525 525);
DISPLAY INVISIBLE (-525 525);
FORCEPROP 2 LAST CDS_LIB pure_quanta_power
J 0
(-425 450);
DISPLAY INVISIBLE (-425 450);
FORCEPROP 1 LAST HDL_POWER GND
J 0
(-425 600);
DISPLAY 0.851064 (-425 600);
PAINT GREEN (-425 600);
DISPLAY INVISIBLE (-425 600);
FORCEPROP 1 LAST PATH I115
J 0
(-350 450);
DISPLAY 0.872340 (-350 450);
PAINT AQUA (-350 450);
DISPLAY INVISIBLE (-350 450);
FORCEADD Q_RES..2
(-425 750);
FORCEPROP 1 LAST LOCATION R1409
J 0
(-380 875);
DISPLAY 0.787234 (-380 875);
FORCEPROP 0 LAST $SEC 1
J 0
(-375 925);
DISPLAY 0.680851 (-375 925);
PAINT MONO (-375 925);
DISPLAY INVISIBLE (-375 925);
FORCEPROP 0 LAST CDS_SEC 1
J 0
(-375 925);
DISPLAY 0.680851 (-375 925);
DISPLAY INVISIBLE (-375 925);
FORCEPROP 1 LASTPIN (-425 850) $PN 1
J 0
(-420 812);
DISPLAY 0.787234 (-420 812);
PAINT MONO (-420 812);
FORCEPROP 1 LASTPIN (-425 650) $PN 2
J 0
(-420 660);
DISPLAY 0.787234 (-420 660);
PAINT MONO (-420 660);
FORCEPROP 1 LAST PACK_TYPE 0201LF
J 0
(-385 575);
DISPLAY 0.787234 (-385 575);
FORCEPROP 1 LAST MATERIAL CHIP
J 0
(-385 675);
DISPLAY 0.787234 (-385 675);
FORCEPROP 1 LAST WATTAGE 1/20W
J 0
(-385 725);
DISPLAY 0.787234 (-385 725);
FORCEPROP 1 LAST VALUE 4.7K
J 0
(-380 825);
DISPLAY 0.787234 (-380 825);
FORCEPROP 1 LAST TOLERANCE 5%
J 0
(-380 775);
DISPLAY 0.787234 (-380 775);
FORCEPROP 2 LAST CDS_LIB pure_quanta
J 0
(-425 750);
DISPLAY INVISIBLE (-425 750);
FORCEPROP 1 LAST PATH I117
J 0
(-375 925);
DISPLAY 0.978723 (-375 925);
PAINT WHITE (-375 925);
DISPLAY INVISIBLE (-375 925);
FORCEPROP 1 LAST PART_NUMBER CS24701JE04
J 0
(-385 625);
DISPLAY 0.978723 (-385 625);
DISPLAY INVISIBLE (-385 625);
FORCEADD Q_RES..2
(-700 1375);
FORCEPROP 1 LAST LOCATION R1484
J 0
(-655 1500);
DISPLAY 0.978723 (-655 1500);
FORCEPROP 0 LAST $SEC 1
J 0
(-650 1550);
DISPLAY 0.680851 (-650 1550);
PAINT MONO (-650 1550);
DISPLAY INVISIBLE (-650 1550);
FORCEPROP 0 LAST CDS_SEC 1
J 0
(-650 1550);
DISPLAY 0.680851 (-650 1550);
DISPLAY INVISIBLE (-650 1550);
FORCEPROP 1 LASTPIN (-700 1475) $PN 1
J 0
(-695 1437);
DISPLAY 0.787234 (-695 1437);
PAINT MONO (-695 1437);
FORCEPROP 1 LASTPIN (-700 1275) $PN 2
J 0
(-695 1285);
DISPLAY 0.787234 (-695 1285);
PAINT MONO (-695 1285);
FORCEPROP 1 LAST VALUE 1K
J 0
(-655 1450);
DISPLAY 0.787234 (-655 1450);
FORCEPROP 1 LAST TOLERANCE 1%
J 0
(-655 1400);
DISPLAY 0.787234 (-655 1400);
FORCEPROP 1 LAST WATTAGE 1/20W
J 0
(-660 1350);
DISPLAY 0.787234 (-660 1350);
FORCEPROP 1 LAST PACK_TYPE 0201LF
J 0
(-660 1200);
DISPLAY 0.787234 (-660 1200);
FORCEPROP 1 LAST MATERIAL EMPTY
J 0
(-660 1300);
DISPLAY 0.787234 (-660 1300);
PAINT RED (-660 1300);
FORCEPROP 2 LAST CDS_LIB pure_quanta
J 0
(-700 1375);
DISPLAY INVISIBLE (-700 1375);
FORCEPROP 1 LAST PATH I118
J 0
(-650 1550);
DISPLAY 0.978723 (-650 1550);
PAINT WHITE (-650 1550);
DISPLAY INVISIBLE (-650 1550);
FORCEPROP 1 LAST PART_NUMBER CS21001FE07
J 0
(-660 1250);
DISPLAY 0.978723 (-660 1250);
DISPLAY INVISIBLE (-660 1250);
FORCEADD Q_RES..2
(-425 1400);
FORCEPROP 1 LAST LOCATION R1485
J 0
(-380 1525);
DISPLAY 0.787234 (-380 1525);
FORCEPROP 0 LAST $SEC 1
J 0
(-375 1575);
DISPLAY 0.680851 (-375 1575);
PAINT MONO (-375 1575);
DISPLAY INVISIBLE (-375 1575);
FORCEPROP 0 LAST CDS_SEC 1
J 0
(-375 1575);
DISPLAY 0.680851 (-375 1575);
DISPLAY INVISIBLE (-375 1575);
FORCEPROP 1 LASTPIN (-425 1500) $PN 1
J 0
(-420 1462);
DISPLAY 0.787234 (-420 1462);
PAINT MONO (-420 1462);
FORCEPROP 1 LASTPIN (-425 1300) $PN 2
J 0
(-420 1310);
DISPLAY 0.787234 (-420 1310);
PAINT MONO (-420 1310);
FORCEPROP 1 LAST WATTAGE 1/20W
J 0
(-385 1375);
DISPLAY 0.787234 (-385 1375);
FORCEPROP 1 LAST MATERIAL EMPTY
J 0
(-385 1325);
DISPLAY 0.787234 (-385 1325);
PAINT RED (-385 1325);
FORCEPROP 1 LAST TOLERANCE 5%
J 0
(-380 1425);
DISPLAY 0.787234 (-380 1425);
FORCEPROP 1 LAST PACK_TYPE 0201LF
J 0
(-375 1250);
DISPLAY 0.787234 (-375 1250);
FORCEPROP 1 LAST VALUE 4.7K
J 0
(-380 1475);
DISPLAY 0.787234 (-380 1475);
FORCEPROP 2 LAST CDS_LIB pure_quanta
J 2
(-425 1400);
DISPLAY INVISIBLE (-425 1400);
FORCEPROP 1 LAST PATH I119
J 0
(-375 1575);
DISPLAY 0.978723 (-375 1575);
PAINT WHITE (-375 1575);
DISPLAY INVISIBLE (-375 1575);
FORCEPROP 1 LAST PART_NUMBER CS24701JE04
J 0
(-385 1275);
DISPLAY 0.978723 (-385 1275);
DISPLAY INVISIBLE (-385 1275);
FORCEADD P1V0..1
(-8950 6400);
FORCEPROP 3 LASTPIN (-8950 6350) SIG_NAME P1V8_CPU0_RT_1D\g
J 0
(-8940 6360);
DISPLAY 0.659574 (-8940 6360);
PAINT MONO (-8940 6360);
DISPLAY INVISIBLE (-8940 6360);
FORCEPROP 1 LAST HDL_POWER P1V8_CPU0_RT_1D
J 1
(-8950 6450);
DISPLAY 0.489362 (-8950 6450);
PAINT SKYBLUE (-8950 6450);
FORCEPROP 2 LAST CDS_LIB pure_quanta_power
J 0
(-8950 6400);
DISPLAY INVISIBLE (-8950 6400);
FORCEPROP 1 LAST PATH I12
J 0
(-8900 6425);
DISPLAY 0.872340 (-8900 6425);
PAINT AQUA (-8900 6425);
DISPLAY INVISIBLE (-8900 6425);
FORCEADD P1V0..1
(-425 1700);
FORCEPROP 3 LASTPIN (-425 1650) SIG_NAME P1V8_CPU0_RT_1D\g
J 0
(-415 1660);
DISPLAY 0.659574 (-415 1660);
PAINT MONO (-415 1660);
DISPLAY INVISIBLE (-415 1660);
FORCEPROP 1 LAST HDL_POWER P1V8_CPU0_RT_1D
J 1
(-425 1750);
DISPLAY 0.489362 (-425 1750);
PAINT SKYBLUE (-425 1750);
FORCEPROP 2 LAST CDS_LIB pure_quanta_power
J 0
(-425 1700);
DISPLAY INVISIBLE (-425 1700);
FORCEPROP 1 LAST PATH I120
J 0
(-375 1725);
DISPLAY 0.872340 (-375 1725);
PAINT AQUA (-375 1725);
DISPLAY INVISIBLE (-375 1725);
FORCEADD OFFPAGE..5
(-2400 1025);
FORCEPROP 2 LAST $XR0 310 
J 0
(-2655 1025);
DISPLAY 0.638298 (-2655 1025);
PAINT MONO (-2655 1025);
FORCEPROP 2 LAST CDS_LIB standard
J 0
(-2400 1025);
DISPLAY INVISIBLE (-2400 1025);
FORCEPROP 1 LAST OFFPAGE TRUE
J 0
(-2075 900);
DISPLAY 0.872340 (-2075 900);
PAINT GREEN (-2075 900);
DISPLAY INVISIBLE (-2075 900);
FORCEPROP 1 LAST COMMENT_BODY TRUE
J 0
(-2300 950);
DISPLAY 0.872340 (-2300 950);
PAINT GREEN (-2300 950);
DISPLAY INVISIBLE (-2300 950);
FORCEPROP 2 LAST PATH I121
J 0
(-2350 1100);
DISPLAY 0.680851 (-2350 1100);
DISPLAY INVISIBLE (-2350 1100);
FORCEADD OFFPAGE..5
(-2400 975);
FORCEPROP 2 LAST $XR0 310 
J 0
(-2655 975);
DISPLAY 0.638298 (-2655 975);
PAINT MONO (-2655 975);
FORCEPROP 2 LAST CDS_LIB standard
J 0
(-2400 975);
DISPLAY INVISIBLE (-2400 975);
FORCEPROP 1 LAST OFFPAGE TRUE
J 0
(-2075 850);
DISPLAY 0.872340 (-2075 850);
PAINT GREEN (-2075 850);
DISPLAY INVISIBLE (-2075 850);
FORCEPROP 1 LAST COMMENT_BODY TRUE
J 0
(-2300 900);
DISPLAY 0.872340 (-2300 900);
PAINT GREEN (-2300 900);
DISPLAY INVISIBLE (-2300 900);
FORCEPROP 2 LAST PATH I123
J 0
(-2350 1050);
DISPLAY 0.680851 (-2350 1050);
DISPLAY INVISIBLE (-2350 1050);
FORCEADD OFFPAGE..1
R 2
(-2750 3350);
FORCEPROP 2 LAST $XR0 310 
J 0
(-2564 3350);
DISPLAY 0.638298 (-2564 3350);
PAINT MONO (-2564 3350);
FORCEPROP 2 LAST CDS_LIB standard
J 0
(-2750 3350);
DISPLAY INVISIBLE (-2750 3350);
FORCEPROP 1 LAST OFFPAGE TRUE
J 2
(-3075 3225);
DISPLAY 0.872340 (-3075 3225);
DISPLAY INVISIBLE (-3075 3225);
FORCEPROP 1 LAST COMMENT_BODY TRUE
J 2
(-2875 3250);
DISPLAY 0.872340 (-2875 3250);
PAINT GREEN (-2875 3250);
DISPLAY INVISIBLE (-2875 3250);
FORCEPROP 2 LAST PATH I125
J 0
(-2575 3425);
DISPLAY 0.680851 (-2575 3425);
DISPLAY INVISIBLE (-2575 3425);
FORCEADD OFFPAGE..1
R 2
(-2725 3450);
FORCEPROP 2 LAST $XR0 310 
J 0
(-2539 3450);
DISPLAY 0.638298 (-2539 3450);
PAINT MONO (-2539 3450);
FORCEPROP 2 LAST CDS_LIB standard
J 0
(-2725 3450);
DISPLAY INVISIBLE (-2725 3450);
FORCEPROP 1 LAST OFFPAGE TRUE
J 2
(-3050 3325);
DISPLAY 0.872340 (-3050 3325);
DISPLAY INVISIBLE (-3050 3325);
FORCEPROP 1 LAST COMMENT_BODY TRUE
J 2
(-2850 3350);
DISPLAY 0.872340 (-2850 3350);
PAINT GREEN (-2850 3350);
DISPLAY INVISIBLE (-2850 3350);
FORCEPROP 2 LAST PATH I126
J 0
(-2550 3525);
DISPLAY 0.680851 (-2550 3525);
DISPLAY INVISIBLE (-2550 3525);
FORCEADD OFFPAGE..1
R 2
(-2725 3550);
FORCEPROP 2 LAST $XR0 310 
J 0
(-2539 3550);
DISPLAY 0.638298 (-2539 3550);
PAINT MONO (-2539 3550);
FORCEPROP 2 LAST CDS_LIB standard
J 0
(-2725 3550);
DISPLAY INVISIBLE (-2725 3550);
FORCEPROP 1 LAST OFFPAGE TRUE
J 2
(-3050 3425);
DISPLAY 0.872340 (-3050 3425);
DISPLAY INVISIBLE (-3050 3425);
FORCEPROP 1 LAST COMMENT_BODY TRUE
J 2
(-2850 3450);
DISPLAY 0.872340 (-2850 3450);
PAINT GREEN (-2850 3450);
DISPLAY INVISIBLE (-2850 3450);
FORCEPROP 2 LAST PATH I127
J 0
(-2550 3625);
DISPLAY 0.680851 (-2550 3625);
DISPLAY INVISIBLE (-2550 3625);
FORCEADD OFFPAGE..1
R 2
(-2725 3650);
FORCEPROP 2 LAST $XR0 310 
J 0
(-2539 3650);
DISPLAY 0.638298 (-2539 3650);
PAINT MONO (-2539 3650);
FORCEPROP 2 LAST CDS_LIB standard
J 0
(-2725 3650);
DISPLAY INVISIBLE (-2725 3650);
FORCEPROP 1 LAST OFFPAGE TRUE
J 2
(-3050 3525);
DISPLAY 0.872340 (-3050 3525);
DISPLAY INVISIBLE (-3050 3525);
FORCEPROP 1 LAST COMMENT_BODY TRUE
J 2
(-2850 3550);
DISPLAY 0.872340 (-2850 3550);
PAINT GREEN (-2850 3550);
DISPLAY INVISIBLE (-2850 3550);
FORCEPROP 2 LAST PATH I128
J 0
(-2550 3725);
DISPLAY 0.680851 (-2550 3725);
DISPLAY INVISIBLE (-2550 3725);
FORCEADD OFFPAGE..3
R 2
(-7775 1550);
FORCEPROP 2 LAST $XR1 186 
J 0
(-8175 1550);
DISPLAY 0.638298 (-8175 1550);
PAINT MONO (-8175 1550);
FORCEPROP 2 LAST $XR0 185 
J 0
(-8055 1550);
DISPLAY 0.638298 (-8055 1550);
PAINT MONO (-8055 1550);
FORCEPROP 2 LAST CDS_LIB standard
J 0
(-7775 1550);
DISPLAY INVISIBLE (-7775 1550);
FORCEPROP 1 LAST OFFPAGE TRUE
J 2
(-8100 1425);
DISPLAY 0.872340 (-8100 1425);
PAINT GREEN (-8100 1425);
DISPLAY INVISIBLE (-8100 1425);
FORCEPROP 1 LAST COMMENT_BODY TRUE
J 2
(-7725 1450);
DISPLAY 0.872340 (-7725 1450);
PAINT GREEN (-7725 1450);
DISPLAY INVISIBLE (-7725 1450);
FORCEPROP 2 LAST PATH I13
J 0
(-8050 1600);
DISPLAY 0.680851 (-8050 1600);
DISPLAY INVISIBLE (-8050 1600);
FORCEADD OFFPAGE..5
(-7775 1650);
FORCEPROP 2 LAST $XR1 186 
J 0
(-8150 1650);
DISPLAY 0.638298 (-8150 1650);
PAINT MONO (-8150 1650);
FORCEPROP 2 LAST $XR0 185 
J 0
(-8030 1650);
DISPLAY 0.638298 (-8030 1650);
PAINT MONO (-8030 1650);
FORCEPROP 2 LAST CDS_LIB standard
J 0
(-7775 1650);
DISPLAY INVISIBLE (-7775 1650);
FORCEPROP 1 LAST OFFPAGE TRUE
J 0
(-7450 1525);
DISPLAY 0.872340 (-7450 1525);
PAINT GREEN (-7450 1525);
DISPLAY INVISIBLE (-7450 1525);
FORCEPROP 1 LAST COMMENT_BODY TRUE
J 0
(-7675 1575);
DISPLAY 0.872340 (-7675 1575);
PAINT GREEN (-7675 1575);
DISPLAY INVISIBLE (-7675 1575);
FORCEPROP 2 LAST PATH I14
J 0
(-8025 1700);
DISPLAY 0.680851 (-8025 1700);
DISPLAY INVISIBLE (-8025 1700);
FORCEADD Q_RES..1
(-6600 1050);
FORCEPROP 1 LAST LOCATION R616
J 0
(-6850 1050);
DISPLAY 0.978723 (-6850 1050);
FORCEPROP 2 LAST SEC 1
J 0
(-6650 1250);
DISPLAY 0.680851 (-6650 1250);
PAINT MONO (-6650 1250);
DISPLAY INVISIBLE (-6650 1250);
FORCEPROP 1 LASTPIN (-6700 1050) $PN 1
J 0
(-6688 1062);
DISPLAY 0.787234 (-6688 1062);
PAINT MONO (-6688 1062);
FORCEPROP 1 LASTPIN (-6500 1050) $PN 2
J 0
(-6538 1062);
DISPLAY 0.787234 (-6538 1062);
PAINT MONO (-6538 1062);
FORCEPROP 1 LAST MATERIAL CHIP
J 0
(-6775 1125);
DISPLAY 0.787234 (-6775 1125);
FORCEPROP 1 LAST PACK_TYPE 0201LF
J 0
(-6575 1125);
DISPLAY 0.787234 (-6575 1125);
FORCEPROP 2 LAST CDS_LIB pure_quanta
J 0
(-6600 1050);
DISPLAY INVISIBLE (-6600 1050);
FORCEPROP 1 LAST TOLERANCE 5%
J 0
(-6775 1175);
DISPLAY 0.787234 (-6775 1175);
DISPLAY INVISIBLE (-6775 1175);
FORCEPROP 1 LAST VALUE 0
J 2
(-6800 1175);
DISPLAY 0.787234 (-6800 1175);
DISPLAY INVISIBLE (-6800 1175);
FORCEPROP 1 LAST WATTAGE 1/20W
J 2
(-6800 1125);
DISPLAY 0.787234 (-6800 1125);
DISPLAY INVISIBLE (-6800 1125);
FORCEPROP 2 LAST SEC_TYPE 0201LF
J 0
(-6650 1250);
DISPLAY 0.680851 (-6650 1250);
DISPLAY INVISIBLE (-6650 1250);
FORCEPROP 1 LAST PATH I15
J 0
(-6650 1200);
DISPLAY 0.978723 (-6650 1200);
PAINT WHITE (-6650 1200);
DISPLAY INVISIBLE (-6650 1200);
FORCEPROP 1 LAST PART_NUMBER CS00001JE10
J 0
(-6650 1175);
DISPLAY 0.808511 (-6650 1175);
DISPLAY INVISIBLE (-6650 1175);
FORCEADD UNIVERSAL_GND..1
(-6300 400);
FORCEPROP 3 LASTPIN (-6300 450) SIG_NAME GND\g
J 0
(-6290 460);
DISPLAY 0.659574 (-6290 460);
PAINT MONO (-6290 460);
DISPLAY INVISIBLE (-6290 460);
FORCEPROP 2 LAST CDS_LIB pure_quanta_power
J 0
(-6300 400);
DISPLAY INVISIBLE (-6300 400);
FORCEPROP 1 LAST HDL_POWER GND
J 1
(-6275 325);
DISPLAY 0.872340 (-6275 325);
PAINT GREEN (-6275 325);
DISPLAY INVISIBLE (-6275 325);
FORCEPROP 1 LAST PATH I16
J 0
(-6225 400);
DISPLAY 0.872340 (-6225 400);
PAINT AQUA (-6225 400);
DISPLAY INVISIBLE (-6225 400);
FORCEADD UNIVERSAL_GND..1
(-6150 400);
FORCEPROP 3 LASTPIN (-6150 450) SIG_NAME GND\g
J 0
(-6140 460);
DISPLAY 0.659574 (-6140 460);
PAINT MONO (-6140 460);
DISPLAY INVISIBLE (-6140 460);
FORCEPROP 2 LAST CDS_LIB pure_quanta_power
J 0
(-6150 400);
DISPLAY INVISIBLE (-6150 400);
FORCEPROP 1 LAST HDL_POWER GND
J 1
(-6125 325);
DISPLAY 0.872340 (-6125 325);
PAINT GREEN (-6125 325);
DISPLAY INVISIBLE (-6125 325);
FORCEPROP 1 LAST PATH I17
J 0
(-6075 400);
DISPLAY 0.872340 (-6075 400);
PAINT AQUA (-6075 400);
DISPLAY INVISIBLE (-6075 400);
FORCEADD Q_RES..2
R 2
(-6300 725);
FORCEPROP 1 LAST LOCATION R635
J 2
(-6345 850);
DISPLAY 0.978723 (-6345 850);
FORCEPROP 0 LAST $SEC 1
J 0
(-6325 900);
DISPLAY 0.680851 (-6325 900);
PAINT MONO (-6325 900);
DISPLAY INVISIBLE (-6325 900);
FORCEPROP 0 LAST CDS_SEC 1
J 0
(-6325 900);
DISPLAY 0.680851 (-6325 900);
DISPLAY INVISIBLE (-6325 900);
FORCEPROP 1 LASTPIN (-6300 825) $PN 1
J 2
(-6305 787);
DISPLAY 0.787234 (-6305 787);
PAINT MONO (-6305 787);
FORCEPROP 1 LASTPIN (-6300 625) $PN 2
J 2
(-6305 635);
DISPLAY 0.787234 (-6305 635);
PAINT MONO (-6305 635);
FORCEPROP 1 LAST TOLERANCE 1%
J 2
(-6345 750);
DISPLAY 0.978723 (-6345 750);
FORCEPROP 1 LAST PACK_TYPE 0201LF
J 2
(-6340 550);
DISPLAY 0.978723 (-6340 550);
FORCEPROP 1 LAST VALUE 51.1
J 2
(-6345 800);
DISPLAY 0.978723 (-6345 800);
FORCEPROP 1 LAST MATERIAL EMPTY
J 2
(-6340 650);
DISPLAY 0.978723 (-6340 650);
FORCEPROP 1 LAST WATTAGE 1/20W
J 2
(-6340 700);
DISPLAY 0.978723 (-6340 700);
FORCEPROP 2 LAST CDS_LIB pure_quanta
J 0
(-6300 725);
DISPLAY INVISIBLE (-6300 725);
FORCEPROP 1 LAST PATH I18
J 2
(-6350 900);
DISPLAY 0.978723 (-6350 900);
PAINT WHITE (-6350 900);
DISPLAY INVISIBLE (-6350 900);
FORCEPROP 1 LAST PART_NUMBER CS05111FE00
J 2
(-6340 600);
DISPLAY 0.978723 (-6340 600);
DISPLAY INVISIBLE (-6340 600);
FORCEADD Q_RES..2
(-6150 725);
FORCEPROP 1 LAST LOCATION R636
J 0
(-6105 850);
DISPLAY 0.978723 (-6105 850);
FORCEPROP 0 LAST $SEC 1
J 0
(-6100 900);
DISPLAY 0.680851 (-6100 900);
PAINT MONO (-6100 900);
DISPLAY INVISIBLE (-6100 900);
FORCEPROP 0 LAST CDS_SEC 1
J 0
(-6100 900);
DISPLAY 0.680851 (-6100 900);
DISPLAY INVISIBLE (-6100 900);
FORCEPROP 1 LASTPIN (-6150 825) $PN 1
J 0
(-6145 787);
DISPLAY 0.787234 (-6145 787);
PAINT MONO (-6145 787);
FORCEPROP 1 LASTPIN (-6150 625) $PN 2
J 0
(-6145 635);
DISPLAY 0.787234 (-6145 635);
PAINT MONO (-6145 635);
FORCEPROP 1 LAST WATTAGE 1/20W
J 0
(-6110 700);
DISPLAY 0.978723 (-6110 700);
FORCEPROP 1 LAST PACK_TYPE 0201LF
J 0
(-6110 550);
DISPLAY 0.978723 (-6110 550);
FORCEPROP 1 LAST MATERIAL EMPTY
J 0
(-6110 650);
DISPLAY 0.978723 (-6110 650);
FORCEPROP 1 LAST VALUE 51.1
J 0
(-6105 800);
DISPLAY 0.978723 (-6105 800);
FORCEPROP 1 LAST TOLERANCE 1%
J 0
(-6105 750);
DISPLAY 0.978723 (-6105 750);
FORCEPROP 2 LAST CDS_LIB pure_quanta
J 0
(-6150 725);
DISPLAY INVISIBLE (-6150 725);
FORCEPROP 1 LAST PATH I19
J 0
(-6100 900);
DISPLAY 0.978723 (-6100 900);
PAINT WHITE (-6100 900);
DISPLAY INVISIBLE (-6100 900);
FORCEPROP 1 LAST PART_NUMBER CS05111FE00
J 0
(-6110 600);
DISPLAY 0.978723 (-6110 600);
DISPLAY INVISIBLE (-6110 600);
FORCEADD OFFPAGE..1
(-8050 1050);
FORCEPROP 2 LAST $XR0 182 
J 0
(-8332 1050);
DISPLAY 0.638298 (-8332 1050);
PAINT MONO (-8332 1050);
FORCEPROP 2 LAST CDS_LIB standard
J 0
(-8050 1050);
DISPLAY INVISIBLE (-8050 1050);
FORCEPROP 1 LAST OFFPAGE TRUE
J 0
(-7725 925);
DISPLAY 0.872340 (-7725 925);
DISPLAY INVISIBLE (-7725 925);
FORCEPROP 1 LAST COMMENT_BODY TRUE
J 0
(-7925 950);
DISPLAY 0.872340 (-7925 950);
PAINT GREEN (-7925 950);
DISPLAY INVISIBLE (-7925 950);
FORCEPROP 2 LAST PATH I2
J 0
(-8325 1100);
DISPLAY 0.680851 (-8325 1100);
DISPLAY INVISIBLE (-8325 1100);
FORCEADD Q_RES..1
(-6600 1200);
FORCEPROP 1 LAST LOCATION R615
J 0
(-6850 1200);
DISPLAY 0.978723 (-6850 1200);
FORCEPROP 2 LAST SEC 1
J 0
(-6650 1400);
DISPLAY 0.680851 (-6650 1400);
PAINT MONO (-6650 1400);
DISPLAY INVISIBLE (-6650 1400);
FORCEPROP 1 LASTPIN (-6700 1200) $PN 1
J 0
(-6688 1212);
DISPLAY 0.787234 (-6688 1212);
PAINT MONO (-6688 1212);
FORCEPROP 1 LASTPIN (-6500 1200) $PN 2
J 0
(-6538 1212);
DISPLAY 0.787234 (-6538 1212);
PAINT MONO (-6538 1212);
FORCEPROP 1 LAST MATERIAL CHIP
J 0
(-6775 1275);
DISPLAY 0.787234 (-6775 1275);
FORCEPROP 1 LAST TOLERANCE 5%
J 0
(-6775 1325);
DISPLAY 0.787234 (-6775 1325);
FORCEPROP 1 LAST PACK_TYPE 0201LF
J 0
(-6575 1275);
DISPLAY 0.787234 (-6575 1275);
FORCEPROP 1 LAST WATTAGE 1/20W
J 2
(-6800 1275);
DISPLAY 0.787234 (-6800 1275);
FORCEPROP 1 LAST VALUE 0
J 2
(-6800 1325);
DISPLAY 0.787234 (-6800 1325);
FORCEPROP 2 LAST CDS_LIB pure_quanta
J 0
(-6600 1200);
DISPLAY INVISIBLE (-6600 1200);
FORCEPROP 0 LAST SEC_TYPE 0201LF
J 0
(-6650 1400);
DISPLAY 0.680851 (-6650 1400);
DISPLAY INVISIBLE (-6650 1400);
FORCEPROP 1 LAST PATH I20
J 0
(-6650 1350);
DISPLAY 0.978723 (-6650 1350);
PAINT WHITE (-6650 1350);
DISPLAY INVISIBLE (-6650 1350);
FORCEPROP 1 LAST PART_NUMBER CS00001JE10
J 0
(-6650 1325);
DISPLAY 0.808511 (-6650 1325);
DISPLAY INVISIBLE (-6650 1325);
FORCEADD Q_RES..1
(-6325 1550);
FORCEPROP 1 LAST LOCATION R686
J 0
(-6575 1575);
DISPLAY 0.978723 (-6575 1575);
FORCEPROP 0 LAST $SEC 1
J 0
(-6475 1625);
DISPLAY 0.680851 (-6475 1625);
PAINT MONO (-6475 1625);
DISPLAY INVISIBLE (-6475 1625);
FORCEPROP 0 LAST CDS_SEC 1
J 0
(-6475 1625);
DISPLAY 0.680851 (-6475 1625);
DISPLAY INVISIBLE (-6475 1625);
FORCEPROP 1 LASTPIN (-6425 1550) $PN 1
J 0
(-6413 1562);
DISPLAY 0.787234 (-6413 1562);
PAINT MONO (-6413 1562);
FORCEPROP 1 LASTPIN (-6225 1550) $PN 2
J 0
(-6263 1562);
DISPLAY 0.787234 (-6263 1562);
PAINT MONO (-6263 1562);
FORCEPROP 2 LAST CDS_LIB pure_quanta
J 0
(-6325 1550);
DISPLAY INVISIBLE (-6325 1550);
FORCEPROP 1 LAST MATERIAL CHIP
J 0
(-6500 1625);
DISPLAY 0.787234 (-6500 1625);
DISPLAY INVISIBLE (-6500 1625);
FORCEPROP 1 LAST WATTAGE 1/20W
J 2
(-6525 1625);
DISPLAY 0.787234 (-6525 1625);
DISPLAY INVISIBLE (-6525 1625);
FORCEPROP 1 LAST PACK_TYPE 0201LF
J 0
(-6300 1625);
DISPLAY 0.787234 (-6300 1625);
DISPLAY INVISIBLE (-6300 1625);
FORCEPROP 1 LAST VALUE 49.9
J 2
(-6525 1675);
DISPLAY 0.787234 (-6525 1675);
DISPLAY INVISIBLE (-6525 1675);
FORCEPROP 1 LAST TOLERANCE 1%
J 0
(-6500 1675);
DISPLAY 0.787234 (-6500 1675);
DISPLAY INVISIBLE (-6500 1675);
FORCEPROP 1 LAST PATH I21
J 0
(-6375 1700);
DISPLAY 0.978723 (-6375 1700);
PAINT WHITE (-6375 1700);
DISPLAY INVISIBLE (-6375 1700);
FORCEPROP 1 LAST PART_NUMBER CS04991FE06
J 0
(-6375 1675);
DISPLAY 0.808511 (-6375 1675);
DISPLAY INVISIBLE (-6375 1675);
FORCEADD Q_RES..1
(-6325 1650);
FORCEPROP 1 LAST LOCATION R684
J 0
(-6575 1675);
DISPLAY 0.978723 (-6575 1675);
FORCEPROP 0 LAST $SEC 1
J 0
(-6375 1825);
DISPLAY 0.680851 (-6375 1825);
PAINT MONO (-6375 1825);
DISPLAY INVISIBLE (-6375 1825);
FORCEPROP 0 LAST CDS_SEC 1
J 0
(-6375 1825);
DISPLAY 0.680851 (-6375 1825);
DISPLAY INVISIBLE (-6375 1825);
FORCEPROP 1 LASTPIN (-6425 1650) $PN 1
J 0
(-6413 1662);
DISPLAY 0.787234 (-6413 1662);
PAINT MONO (-6413 1662);
FORCEPROP 1 LASTPIN (-6225 1650) $PN 2
J 0
(-6263 1662);
DISPLAY 0.787234 (-6263 1662);
PAINT MONO (-6263 1662);
FORCEPROP 1 LAST PACK_TYPE 0201LF
J 0
(-6300 1725);
DISPLAY 0.787234 (-6300 1725);
FORCEPROP 1 LAST MATERIAL CHIP
J 0
(-6500 1725);
DISPLAY 0.787234 (-6500 1725);
FORCEPROP 1 LAST WATTAGE 1/20W
J 2
(-6525 1725);
DISPLAY 0.787234 (-6525 1725);
FORCEPROP 1 LAST VALUE 49.9
J 2
(-6525 1775);
DISPLAY 0.787234 (-6525 1775);
FORCEPROP 1 LAST TOLERANCE 1%
J 0
(-6500 1775);
DISPLAY 0.787234 (-6500 1775);
FORCEPROP 2 LAST CDS_LIB pure_quanta
J 0
(-6325 1650);
DISPLAY INVISIBLE (-6325 1650);
FORCEPROP 1 LAST PATH I22
J 0
(-6375 1800);
DISPLAY 0.978723 (-6375 1800);
PAINT WHITE (-6375 1800);
DISPLAY INVISIBLE (-6375 1800);
FORCEPROP 1 LAST PART_NUMBER CS04991FE06
J 0
(-6375 1775);
DISPLAY 0.808511 (-6375 1775);
DISPLAY INVISIBLE (-6375 1775);
FORCEADD OFFPAGE..1
(-6150 2050);
FORCEPROP 2 LAST $XR0 310 
J 0
(-6402 2050);
DISPLAY 0.638298 (-6402 2050);
PAINT MONO (-6402 2050);
FORCEPROP 2 LAST CDS_LIB standard
J 0
(-6150 2050);
DISPLAY INVISIBLE (-6150 2050);
FORCEPROP 1 LAST OFFPAGE TRUE
J 0
(-5825 1925);
DISPLAY 0.872340 (-5825 1925);
DISPLAY INVISIBLE (-5825 1925);
FORCEPROP 1 LAST COMMENT_BODY TRUE
J 0
(-6025 1950);
DISPLAY 0.872340 (-6025 1950);
PAINT GREEN (-6025 1950);
DISPLAY INVISIBLE (-6025 1950);
FORCEPROP 2 LAST PATH I23
J 0
(-6400 2100);
DISPLAY 0.680851 (-6400 2100);
DISPLAY INVISIBLE (-6400 2100);
FORCEADD OFFPAGE..1
(-6150 1950);
FORCEPROP 2 LAST $XR0 310 
J 0
(-6402 1950);
DISPLAY 0.638298 (-6402 1950);
PAINT MONO (-6402 1950);
FORCEPROP 2 LAST CDS_LIB standard
J 0
(-6150 1950);
DISPLAY INVISIBLE (-6150 1950);
FORCEPROP 1 LAST OFFPAGE TRUE
J 0
(-5825 1825);
DISPLAY 0.872340 (-5825 1825);
DISPLAY INVISIBLE (-5825 1825);
FORCEPROP 1 LAST COMMENT_BODY TRUE
J 0
(-6025 1850);
DISPLAY 0.872340 (-6025 1850);
PAINT GREEN (-6025 1850);
DISPLAY INVISIBLE (-6025 1850);
FORCEPROP 2 LAST PATH I24
J 0
(-6400 2000);
DISPLAY 0.680851 (-6400 2000);
DISPLAY INVISIBLE (-6400 2000);
FORCEADD OFFPAGE..1
(-6150 2150);
FORCEPROP 2 LAST $XR0 310 
J 0
(-6402 2150);
DISPLAY 0.638298 (-6402 2150);
PAINT MONO (-6402 2150);
FORCEPROP 2 LAST CDS_LIB standard
J 0
(-6150 2150);
DISPLAY INVISIBLE (-6150 2150);
FORCEPROP 1 LAST OFFPAGE TRUE
J 0
(-5825 2025);
DISPLAY 0.872340 (-5825 2025);
DISPLAY INVISIBLE (-5825 2025);
FORCEPROP 1 LAST COMMENT_BODY TRUE
J 0
(-6025 2050);
DISPLAY 0.872340 (-6025 2050);
PAINT GREEN (-6025 2050);
DISPLAY INVISIBLE (-6025 2050);
FORCEPROP 2 LAST PATH I25
J 0
(-6400 2200);
DISPLAY 0.680851 (-6400 2200);
DISPLAY INVISIBLE (-6400 2200);
FORCEADD OFFPAGE..3
R 2
(-7650 2800);
FORCEPROP 2 LAST $XR0 184 
J 0
(-7930 2800);
DISPLAY 0.638298 (-7930 2800);
PAINT MONO (-7930 2800);
FORCEPROP 2 LAST CDS_LIB standard
J 0
(-7650 2800);
DISPLAY INVISIBLE (-7650 2800);
FORCEPROP 1 LAST OFFPAGE TRUE
J 2
(-7975 2675);
DISPLAY 0.872340 (-7975 2675);
PAINT GREEN (-7975 2675);
DISPLAY INVISIBLE (-7975 2675);
FORCEPROP 1 LAST COMMENT_BODY TRUE
J 2
(-7600 2700);
DISPLAY 0.872340 (-7600 2700);
PAINT GREEN (-7600 2700);
DISPLAY INVISIBLE (-7600 2700);
FORCEPROP 2 LAST PATH I26
J 0
(-7925 2850);
DISPLAY 0.680851 (-7925 2850);
DISPLAY INVISIBLE (-7925 2850);
FORCEADD OFFPAGE..1
(-7650 2900);
FORCEPROP 2 LAST $XR0 184 
J 0
(-7902 2900);
DISPLAY 0.638298 (-7902 2900);
PAINT MONO (-7902 2900);
FORCEPROP 2 LAST CDS_LIB standard
J 0
(-7650 2900);
DISPLAY INVISIBLE (-7650 2900);
FORCEPROP 1 LAST OFFPAGE TRUE
J 0
(-7325 2775);
DISPLAY 0.872340 (-7325 2775);
DISPLAY INVISIBLE (-7325 2775);
FORCEPROP 1 LAST COMMENT_BODY TRUE
J 0
(-7525 2800);
DISPLAY 0.872340 (-7525 2800);
PAINT GREEN (-7525 2800);
DISPLAY INVISIBLE (-7525 2800);
FORCEPROP 2 LAST PATH I27
J 0
(-7900 2950);
DISPLAY 0.680851 (-7900 2950);
DISPLAY INVISIBLE (-7900 2950);
FORCEADD OFFPAGE..5
R 2
(-7800 3900);
FORCEPROP 2 LAST $XR0 310 
J 0
(-7611 3900);
DISPLAY 0.638298 (-7611 3900);
PAINT MONO (-7611 3900);
FORCEPROP 2 LAST CDS_LIB standard
J 0
(-7800 3900);
DISPLAY INVISIBLE (-7800 3900);
FORCEPROP 1 LAST OFFPAGE TRUE
J 2
(-8125 3775);
DISPLAY 0.872340 (-8125 3775);
PAINT GREEN (-8125 3775);
DISPLAY INVISIBLE (-8125 3775);
FORCEPROP 1 LAST COMMENT_BODY TRUE
J 2
(-7900 3825);
DISPLAY 0.872340 (-7900 3825);
PAINT GREEN (-7900 3825);
DISPLAY INVISIBLE (-7900 3825);
FORCEPROP 2 LAST PATH I28
J 0
(-7600 3950);
DISPLAY 0.680851 (-7600 3950);
DISPLAY INVISIBLE (-7600 3950);
FORCEADD OFFPAGE..1
(-5975 2550);
FORCEPROP 2 LAST $XR0 310 
J 0
(-6227 2550);
DISPLAY 0.638298 (-6227 2550);
PAINT MONO (-6227 2550);
FORCEPROP 2 LAST CDS_LIB standard
J 0
(-5975 2550);
DISPLAY INVISIBLE (-5975 2550);
FORCEPROP 1 LAST OFFPAGE TRUE
J 0
(-5650 2425);
DISPLAY 0.872340 (-5650 2425);
DISPLAY INVISIBLE (-5650 2425);
FORCEPROP 1 LAST COMMENT_BODY TRUE
J 0
(-5850 2450);
DISPLAY 0.872340 (-5850 2450);
PAINT GREEN (-5850 2450);
DISPLAY INVISIBLE (-5850 2450);
FORCEPROP 2 LAST PATH I29
J 0
(-6225 2600);
DISPLAY 0.680851 (-6225 2600);
DISPLAY INVISIBLE (-6225 2600);
FORCEADD UNIVERSAL_GND..1
(-8975 3175);
FORCEPROP 3 LASTPIN (-8975 3225) SIG_NAME GND\g
J 0
(-8965 3235);
DISPLAY 0.659574 (-8965 3235);
PAINT MONO (-8965 3235);
DISPLAY INVISIBLE (-8965 3235);
FORCEPROP 2 LAST CDS_LIB pure_quanta_power
J 0
(-8975 3175);
DISPLAY INVISIBLE (-8975 3175);
FORCEPROP 1 LAST HDL_POWER GND
J 1
(-8950 3100);
DISPLAY 0.872340 (-8950 3100);
PAINT GREEN (-8950 3100);
DISPLAY INVISIBLE (-8950 3100);
FORCEPROP 1 LAST PATH I3
J 0
(-8900 3175);
DISPLAY 0.872340 (-8900 3175);
PAINT AQUA (-8900 3175);
DISPLAY INVISIBLE (-8900 3175);
FORCEADD OFFPAGE..1
(-5975 2450);
FORCEPROP 2 LAST $XR0 310 
J 0
(-6227 2450);
DISPLAY 0.638298 (-6227 2450);
PAINT MONO (-6227 2450);
FORCEPROP 2 LAST CDS_LIB standard
J 0
(-5975 2450);
DISPLAY INVISIBLE (-5975 2450);
FORCEPROP 1 LAST OFFPAGE TRUE
J 0
(-5650 2325);
DISPLAY 0.872340 (-5650 2325);
DISPLAY INVISIBLE (-5650 2325);
FORCEPROP 1 LAST COMMENT_BODY TRUE
J 0
(-5850 2350);
DISPLAY 0.872340 (-5850 2350);
PAINT GREEN (-5850 2350);
DISPLAY INVISIBLE (-5850 2350);
FORCEPROP 2 LAST PATH I30
J 0
(-6225 2500);
DISPLAY 0.680851 (-6225 2500);
DISPLAY INVISIBLE (-6225 2500);
FORCEADD OFFPAGE..1
(-5975 2650);
FORCEPROP 2 LAST $XR0 310 
J 0
(-6227 2650);
DISPLAY 0.638298 (-6227 2650);
PAINT MONO (-6227 2650);
FORCEPROP 2 LAST CDS_LIB standard
J 0
(-5975 2650);
DISPLAY INVISIBLE (-5975 2650);
FORCEPROP 1 LAST OFFPAGE TRUE
J 0
(-5650 2525);
DISPLAY 0.872340 (-5650 2525);
DISPLAY INVISIBLE (-5650 2525);
FORCEPROP 1 LAST COMMENT_BODY TRUE
J 0
(-5850 2550);
DISPLAY 0.872340 (-5850 2550);
PAINT GREEN (-5850 2550);
DISPLAY INVISIBLE (-5850 2550);
FORCEPROP 2 LAST PATH I31
J 0
(-6225 2700);
DISPLAY 0.680851 (-6225 2700);
DISPLAY INVISIBLE (-6225 2700);
FORCEADD Q_RES..1
(-6350 2900);
FORCEPROP 1 LAST LOCATION R1109
J 0
(-6600 2925);
DISPLAY 0.978723 (-6600 2925);
FORCEPROP 0 LAST $SEC 1
J 0
(-6400 3075);
DISPLAY 0.680851 (-6400 3075);
PAINT MONO (-6400 3075);
DISPLAY INVISIBLE (-6400 3075);
FORCEPROP 0 LAST CDS_SEC 1
J 0
(-6400 3075);
DISPLAY 0.680851 (-6400 3075);
DISPLAY INVISIBLE (-6400 3075);
FORCEPROP 1 LASTPIN (-6450 2900) $PN 1
J 0
(-6438 2912);
DISPLAY 0.787234 (-6438 2912);
PAINT MONO (-6438 2912);
FORCEPROP 1 LASTPIN (-6250 2900) $PN 2
J 0
(-6288 2912);
DISPLAY 0.787234 (-6288 2912);
PAINT MONO (-6288 2912);
FORCEPROP 1 LAST VALUE 0
J 2
(-6550 3025);
DISPLAY 0.787234 (-6550 3025);
FORCEPROP 1 LAST PACK_TYPE 0201LF
J 0
(-6325 2975);
DISPLAY 0.787234 (-6325 2975);
FORCEPROP 1 LAST WATTAGE 1/20W
J 2
(-6550 2975);
DISPLAY 0.787234 (-6550 2975);
FORCEPROP 1 LAST MATERIAL CHIP
J 0
(-6525 2975);
DISPLAY 0.787234 (-6525 2975);
FORCEPROP 1 LAST TOLERANCE 5%
J 0
(-6525 3025);
DISPLAY 0.787234 (-6525 3025);
FORCEPROP 2 LAST CDS_LIB pure_quanta
J 0
(-6350 2900);
DISPLAY INVISIBLE (-6350 2900);
FORCEPROP 1 LAST PATH I32
J 0
(-6400 3050);
DISPLAY 0.978723 (-6400 3050);
PAINT WHITE (-6400 3050);
DISPLAY INVISIBLE (-6400 3050);
FORCEPROP 1 LAST PART_NUMBER CS00001JE10
J 0
(-6400 3025);
DISPLAY 0.808511 (-6400 3025);
DISPLAY INVISIBLE (-6400 3025);
FORCEADD Q_RES..1
(-6350 2800);
FORCEPROP 1 LAST LOCATION R1110
J 0
(-6600 2825);
DISPLAY 0.978723 (-6600 2825);
FORCEPROP 0 LAST $SEC 1
J 0
(-6600 2875);
DISPLAY 0.680851 (-6600 2875);
PAINT MONO (-6600 2875);
DISPLAY INVISIBLE (-6600 2875);
FORCEPROP 0 LAST CDS_SEC 1
J 0
(-6600 2875);
DISPLAY 0.680851 (-6600 2875);
DISPLAY INVISIBLE (-6600 2875);
FORCEPROP 1 LASTPIN (-6450 2800) $PN 1
J 0
(-6438 2812);
DISPLAY 0.787234 (-6438 2812);
PAINT MONO (-6438 2812);
FORCEPROP 1 LASTPIN (-6250 2800) $PN 2
J 0
(-6288 2812);
DISPLAY 0.787234 (-6288 2812);
PAINT MONO (-6288 2812);
FORCEPROP 2 LAST CDS_LIB pure_quanta
J 0
(-6350 2800);
DISPLAY INVISIBLE (-6350 2800);
FORCEPROP 1 LAST PACK_TYPE 0201LF
J 0
(-6325 2875);
DISPLAY 0.787234 (-6325 2875);
DISPLAY INVISIBLE (-6325 2875);
FORCEPROP 1 LAST MATERIAL CHIP
J 0
(-6525 2875);
DISPLAY 0.787234 (-6525 2875);
DISPLAY INVISIBLE (-6525 2875);
FORCEPROP 1 LAST TOLERANCE 5%
J 0
(-6525 2925);
DISPLAY 0.787234 (-6525 2925);
DISPLAY INVISIBLE (-6525 2925);
FORCEPROP 1 LAST VALUE 0
J 2
(-6550 2925);
DISPLAY 0.787234 (-6550 2925);
DISPLAY INVISIBLE (-6550 2925);
FORCEPROP 1 LAST WATTAGE 1/20W
J 2
(-6550 2875);
DISPLAY 0.787234 (-6550 2875);
DISPLAY INVISIBLE (-6550 2875);
FORCEPROP 1 LAST PATH I33
J 0
(-6400 2950);
DISPLAY 0.978723 (-6400 2950);
PAINT WHITE (-6400 2950);
DISPLAY INVISIBLE (-6400 2950);
FORCEPROP 1 LAST PART_NUMBER CS00001JE10
J 0
(-6400 2925);
DISPLAY 0.808511 (-6400 2925);
DISPLAY INVISIBLE (-6400 2925);
FORCEADD OFFPAGE..1
(-6025 3350);
FORCEPROP 2 LAST $XR0 310 
J 0
(-6307 3350);
DISPLAY 0.638298 (-6307 3350);
PAINT MONO (-6307 3350);
FORCEPROP 2 LAST CDS_LIB standard
J 0
(-6025 3350);
DISPLAY INVISIBLE (-6025 3350);
FORCEPROP 1 LAST OFFPAGE TRUE
J 0
(-5700 3225);
DISPLAY 0.872340 (-5700 3225);
DISPLAY INVISIBLE (-5700 3225);
FORCEPROP 1 LAST COMMENT_BODY TRUE
J 0
(-5900 3250);
DISPLAY 0.872340 (-5900 3250);
PAINT GREEN (-5900 3250);
DISPLAY INVISIBLE (-5900 3250);
FORCEPROP 2 LAST PATH I34
J 0
(-6300 3400);
DISPLAY 0.680851 (-6300 3400);
DISPLAY INVISIBLE (-6300 3400);
FORCEADD OFFPAGE..1
(-6025 3250);
FORCEPROP 2 LAST $XR0 310 
J 0
(-6307 3250);
DISPLAY 0.638298 (-6307 3250);
PAINT MONO (-6307 3250);
FORCEPROP 2 LAST CDS_LIB standard
J 0
(-6025 3250);
DISPLAY INVISIBLE (-6025 3250);
FORCEPROP 1 LAST OFFPAGE TRUE
J 0
(-5700 3125);
DISPLAY 0.872340 (-5700 3125);
DISPLAY INVISIBLE (-5700 3125);
FORCEPROP 1 LAST COMMENT_BODY TRUE
J 0
(-5900 3150);
DISPLAY 0.872340 (-5900 3150);
PAINT GREEN (-5900 3150);
DISPLAY INVISIBLE (-5900 3150);
FORCEPROP 2 LAST PATH I35
J 0
(-6300 3300);
DISPLAY 0.680851 (-6300 3300);
DISPLAY INVISIBLE (-6300 3300);
FORCEADD Q_RES..2
(-8025 5025);
FORCEPROP 1 LAST LOCATION R1118
J 0
(-7980 5150);
DISPLAY 0.787234 (-7980 5150);
FORCEPROP 0 LAST $SEC 1
J 0
(-7975 5200);
DISPLAY 0.680851 (-7975 5200);
PAINT MONO (-7975 5200);
DISPLAY INVISIBLE (-7975 5200);
FORCEPROP 0 LAST CDS_SEC 1
J 0
(-7975 5200);
DISPLAY 0.680851 (-7975 5200);
DISPLAY INVISIBLE (-7975 5200);
FORCEPROP 1 LASTPIN (-8025 5125) $PN 1
J 0
(-8020 5087);
DISPLAY 0.787234 (-8020 5087);
PAINT MONO (-8020 5087);
FORCEPROP 1 LASTPIN (-8025 4925) $PN 2
J 0
(-8020 4935);
DISPLAY 0.787234 (-8020 4935);
PAINT MONO (-8020 4935);
FORCEPROP 1 LAST TOLERANCE 5%
J 0
(-7980 5050);
DISPLAY 0.787234 (-7980 5050);
FORCEPROP 1 LAST VALUE 4.7K
J 0
(-7980 5100);
DISPLAY 0.787234 (-7980 5100);
FORCEPROP 1 LAST PACK_TYPE 0201LF
J 0
(-7985 4850);
DISPLAY 0.787234 (-7985 4850);
FORCEPROP 1 LAST WATTAGE 1/20W
J 0
(-7985 5000);
DISPLAY 0.787234 (-7985 5000);
FORCEPROP 1 LAST MATERIAL CHIP
J 0
(-7985 4950);
DISPLAY 0.787234 (-7985 4950);
FORCEPROP 2 LAST CDS_LIB pure_quanta
J 0
(-8025 5025);
DISPLAY INVISIBLE (-8025 5025);
FORCEPROP 1 LAST PATH I36
J 0
(-7975 5200);
DISPLAY 0.978723 (-7975 5200);
PAINT WHITE (-7975 5200);
DISPLAY INVISIBLE (-7975 5200);
FORCEPROP 1 LAST PART_NUMBER CS24701JE04
J 0
(-7985 4900);
DISPLAY 0.978723 (-7985 4900);
DISPLAY INVISIBLE (-7985 4900);
FORCEADD Q_RES..2
(-7725 5025);
FORCEPROP 1 LAST LOCATION R1120
J 0
(-7680 5150);
DISPLAY 0.787234 (-7680 5150);
FORCEPROP 0 LAST $SEC 1
J 0
(-7675 5200);
DISPLAY 0.680851 (-7675 5200);
PAINT MONO (-7675 5200);
DISPLAY INVISIBLE (-7675 5200);
FORCEPROP 0 LAST CDS_SEC 1
J 0
(-7675 5200);
DISPLAY 0.680851 (-7675 5200);
DISPLAY INVISIBLE (-7675 5200);
FORCEPROP 1 LASTPIN (-7725 5125) $PN 1
J 0
(-7720 5087);
DISPLAY 0.787234 (-7720 5087);
PAINT MONO (-7720 5087);
FORCEPROP 1 LASTPIN (-7725 4925) $PN 2
J 0
(-7720 4935);
DISPLAY 0.787234 (-7720 4935);
PAINT MONO (-7720 4935);
FORCEPROP 1 LAST MATERIAL CHIP
J 0
(-7685 4950);
DISPLAY 0.787234 (-7685 4950);
FORCEPROP 1 LAST VALUE 4.7K
J 0
(-7680 5100);
DISPLAY 0.787234 (-7680 5100);
FORCEPROP 1 LAST TOLERANCE 5%
J 0
(-7680 5050);
DISPLAY 0.787234 (-7680 5050);
FORCEPROP 1 LAST WATTAGE 1/20W
J 0
(-7685 5000);
DISPLAY 0.787234 (-7685 5000);
FORCEPROP 1 LAST PACK_TYPE 0201LF
J 0
(-7685 4850);
DISPLAY 0.787234 (-7685 4850);
FORCEPROP 2 LAST CDS_LIB pure_quanta
J 0
(-7725 5025);
DISPLAY INVISIBLE (-7725 5025);
FORCEPROP 1 LAST PATH I37
J 0
(-7675 5200);
DISPLAY 0.978723 (-7675 5200);
PAINT WHITE (-7675 5200);
DISPLAY INVISIBLE (-7675 5200);
FORCEPROP 1 LAST PART_NUMBER CS24701JE04
J 0
(-7685 4900);
DISPLAY 0.787234 (-7685 4900);
DISPLAY INVISIBLE (-7685 4900);
FORCEADD UNIVERSAL_GND..1
(-7425 4550);
FORCEPROP 3 LASTPIN (-7425 4600) SIG_NAME GND\g
J 0
(-7415 4610);
DISPLAY 0.659574 (-7415 4610);
PAINT MONO (-7415 4610);
DISPLAY INVISIBLE (-7415 4610);
FORCEPROP 2 LAST CDS_LIB pure_quanta_power
J 0
(-7425 4550);
DISPLAY INVISIBLE (-7425 4550);
FORCEPROP 1 LAST HDL_POWER GND
J 1
(-7400 4475);
DISPLAY 0.872340 (-7400 4475);
PAINT GREEN (-7400 4475);
DISPLAY INVISIBLE (-7400 4475);
FORCEPROP 1 LAST PATH I38
J 0
(-7350 4550);
DISPLAY 0.872340 (-7350 4550);
PAINT AQUA (-7350 4550);
DISPLAY INVISIBLE (-7350 4550);
FORCEADD Q_RES..2
(-7425 5000);
FORCEPROP 1 LAST LOCATION R1121
J 0
(-7380 5125);
DISPLAY 0.787234 (-7380 5125);
FORCEPROP 0 LAST $SEC 1
J 0
(-7375 5175);
DISPLAY 0.680851 (-7375 5175);
PAINT MONO (-7375 5175);
DISPLAY INVISIBLE (-7375 5175);
FORCEPROP 0 LAST CDS_SEC 1
J 0
(-7375 5175);
DISPLAY 0.680851 (-7375 5175);
DISPLAY INVISIBLE (-7375 5175);
FORCEPROP 1 LASTPIN (-7425 5100) $PN 1
J 0
(-7420 5062);
DISPLAY 0.787234 (-7420 5062);
PAINT MONO (-7420 5062);
FORCEPROP 1 LASTPIN (-7425 4900) $PN 2
J 0
(-7420 4910);
DISPLAY 0.787234 (-7420 4910);
PAINT MONO (-7420 4910);
FORCEPROP 1 LAST VALUE 4.7K
J 0
(-7380 5075);
DISPLAY 0.787234 (-7380 5075);
FORCEPROP 1 LAST TOLERANCE 5%
J 0
(-7380 5025);
DISPLAY 0.787234 (-7380 5025);
FORCEPROP 1 LAST WATTAGE 1/20W
J 0
(-7385 4975);
DISPLAY 0.787234 (-7385 4975);
FORCEPROP 1 LAST MATERIAL CHIP
J 0
(-7385 4925);
DISPLAY 0.787234 (-7385 4925);
FORCEPROP 1 LAST PACK_TYPE 0201LF
J 0
(-7385 4825);
DISPLAY 0.787234 (-7385 4825);
FORCEPROP 2 LAST CDS_LIB pure_quanta
J 0
(-7425 5000);
DISPLAY INVISIBLE (-7425 5000);
FORCEPROP 1 LAST PATH I39
J 0
(-7375 5175);
DISPLAY 0.978723 (-7375 5175);
PAINT WHITE (-7375 5175);
DISPLAY INVISIBLE (-7375 5175);
FORCEPROP 1 LAST PART_NUMBER CS24701JE04
J 0
(-7385 4875);
DISPLAY 0.638298 (-7385 4875);
DISPLAY INVISIBLE (-7385 4875);
FORCEADD Q_RES..2
(-8025 5950);
FORCEPROP 1 LAST LOCATION R1116
J 0
(-7980 6075);
DISPLAY 0.787234 (-7980 6075);
FORCEPROP 0 LAST $SEC 1
J 0
(-7975 6125);
DISPLAY 0.680851 (-7975 6125);
PAINT MONO (-7975 6125);
DISPLAY INVISIBLE (-7975 6125);
FORCEPROP 0 LAST CDS_SEC 1
J 0
(-7975 6125);
DISPLAY 0.680851 (-7975 6125);
DISPLAY INVISIBLE (-7975 6125);
FORCEPROP 1 LASTPIN (-8025 6050) $PN 1
J 0
(-8020 6012);
DISPLAY 0.787234 (-8020 6012);
PAINT MONO (-8020 6012);
FORCEPROP 1 LASTPIN (-8025 5850) $PN 2
J 0
(-8020 5860);
DISPLAY 0.787234 (-8020 5860);
PAINT MONO (-8020 5860);
FORCEPROP 1 LAST TOLERANCE 5%
J 0
(-7980 5975);
DISPLAY 0.787234 (-7980 5975);
FORCEPROP 1 LAST PACK_TYPE 0201LF
J 0
(-7975 5800);
DISPLAY 0.787234 (-7975 5800);
FORCEPROP 1 LAST MATERIAL EMPTY
J 0
(-7985 5875);
DISPLAY 0.787234 (-7985 5875);
FORCEPROP 1 LAST WATTAGE 1/20W
J 0
(-7985 5925);
DISPLAY 0.787234 (-7985 5925);
FORCEPROP 1 LAST VALUE 4.7K
J 0
(-7980 6025);
DISPLAY 0.787234 (-7980 6025);
FORCEPROP 2 LAST CDS_LIB pure_quanta
J 0
(-8025 5950);
DISPLAY INVISIBLE (-8025 5950);
FORCEPROP 1 LAST PATH I40
J 0
(-7975 6125);
DISPLAY 0.978723 (-7975 6125);
PAINT WHITE (-7975 6125);
DISPLAY INVISIBLE (-7975 6125);
FORCEPROP 1 LAST PART_NUMBER CS24701JE04
J 0
(-7985 5825);
DISPLAY 0.978723 (-7985 5825);
DISPLAY INVISIBLE (-7985 5825);
FORCEADD Q_RES..2
(-7725 5975);
FORCEPROP 1 LAST LOCATION R1119
J 0
(-7680 6100);
DISPLAY 0.787234 (-7680 6100);
FORCEPROP 0 LAST $SEC 1
J 0
(-7675 6150);
DISPLAY 0.680851 (-7675 6150);
PAINT MONO (-7675 6150);
DISPLAY INVISIBLE (-7675 6150);
FORCEPROP 0 LAST CDS_SEC 1
J 0
(-7675 6150);
DISPLAY 0.680851 (-7675 6150);
DISPLAY INVISIBLE (-7675 6150);
FORCEPROP 1 LASTPIN (-7725 6075) $PN 1
J 0
(-7720 6037);
DISPLAY 0.787234 (-7720 6037);
PAINT MONO (-7720 6037);
FORCEPROP 1 LASTPIN (-7725 5875) $PN 2
J 0
(-7720 5885);
DISPLAY 0.787234 (-7720 5885);
PAINT MONO (-7720 5885);
FORCEPROP 1 LAST WATTAGE 1/20W
J 0
(-7685 5950);
DISPLAY 0.787234 (-7685 5950);
FORCEPROP 1 LAST MATERIAL EMPTY
J 0
(-7685 5900);
DISPLAY 0.787234 (-7685 5900);
FORCEPROP 1 LAST TOLERANCE 5%
J 0
(-7680 6000);
DISPLAY 0.787234 (-7680 6000);
FORCEPROP 1 LAST PACK_TYPE 0201LF
J 0
(-7685 5800);
DISPLAY 0.787234 (-7685 5800);
FORCEPROP 1 LAST VALUE 4.7K
J 0
(-7680 6050);
DISPLAY 0.787234 (-7680 6050);
FORCEPROP 2 LAST CDS_LIB pure_quanta
J 0
(-7725 5975);
DISPLAY INVISIBLE (-7725 5975);
FORCEPROP 1 LAST PATH I41
J 0
(-7675 6150);
DISPLAY 0.978723 (-7675 6150);
PAINT WHITE (-7675 6150);
DISPLAY INVISIBLE (-7675 6150);
FORCEPROP 1 LAST PART_NUMBER CS24701JE04
J 0
(-7685 5850);
DISPLAY 0.787234 (-7685 5850);
DISPLAY INVISIBLE (-7685 5850);
FORCEADD Q_RES..2
(-7425 6000);
FORCEPROP 1 LAST LOCATION R1108
J 0
(-7380 6125);
DISPLAY 0.787234 (-7380 6125);
FORCEPROP 0 LAST $SEC 1
J 0
(-7375 6175);
DISPLAY 0.680851 (-7375 6175);
PAINT MONO (-7375 6175);
DISPLAY INVISIBLE (-7375 6175);
FORCEPROP 0 LAST CDS_SEC 1
J 0
(-7375 6175);
DISPLAY 0.680851 (-7375 6175);
DISPLAY INVISIBLE (-7375 6175);
FORCEPROP 1 LASTPIN (-7425 6100) $PN 1
J 0
(-7420 6062);
DISPLAY 0.787234 (-7420 6062);
PAINT MONO (-7420 6062);
FORCEPROP 1 LASTPIN (-7425 5900) $PN 2
J 0
(-7420 5910);
DISPLAY 0.787234 (-7420 5910);
PAINT MONO (-7420 5910);
FORCEPROP 1 LAST MATERIAL EMPTY
J 0
(-7385 5925);
DISPLAY 0.787234 (-7385 5925);
FORCEPROP 1 LAST WATTAGE 1/20W
J 0
(-7385 5975);
DISPLAY 0.787234 (-7385 5975);
FORCEPROP 1 LAST TOLERANCE 5%
J 0
(-7380 6025);
DISPLAY 0.787234 (-7380 6025);
FORCEPROP 1 LAST PACK_TYPE 0201LF
J 0
(-7375 5825);
DISPLAY 0.787234 (-7375 5825);
FORCEPROP 1 LAST VALUE 4.7K
J 0
(-7380 6075);
DISPLAY 0.787234 (-7380 6075);
FORCEPROP 2 LAST CDS_LIB pure_quanta
J 0
(-7425 6000);
DISPLAY INVISIBLE (-7425 6000);
FORCEPROP 1 LAST PATH I42
J 0
(-7375 6175);
DISPLAY 0.978723 (-7375 6175);
PAINT WHITE (-7375 6175);
DISPLAY INVISIBLE (-7375 6175);
FORCEPROP 1 LAST PART_NUMBER CS24701JE04
J 0
(-7375 5875);
DISPLAY 0.638298 (-7375 5875);
DISPLAY INVISIBLE (-7375 5875);
FORCEADD OFFPAGE..5
R 2
(-6375 5475);
FORCEPROP 2 LAST $XR0 310 
J 0
(-6186 5475);
DISPLAY 0.638298 (-6186 5475);
PAINT MONO (-6186 5475);
FORCEPROP 2 LAST CDS_LIB standard
J 0
(-6375 5475);
DISPLAY INVISIBLE (-6375 5475);
FORCEPROP 1 LAST OFFPAGE TRUE
J 2
(-6700 5350);
DISPLAY 0.872340 (-6700 5350);
PAINT GREEN (-6700 5350);
DISPLAY INVISIBLE (-6700 5350);
FORCEPROP 1 LAST COMMENT_BODY TRUE
J 2
(-6475 5400);
DISPLAY 0.872340 (-6475 5400);
PAINT GREEN (-6475 5400);
DISPLAY INVISIBLE (-6475 5400);
FORCEPROP 2 LAST PATH I43
J 0
(-6175 5525);
DISPLAY 0.680851 (-6175 5525);
DISPLAY INVISIBLE (-6175 5525);
FORCEADD OFFPAGE..5
R 2
(-6375 5400);
FORCEPROP 2 LAST $XR0 310 
J 0
(-6186 5400);
DISPLAY 0.638298 (-6186 5400);
PAINT MONO (-6186 5400);
FORCEPROP 2 LAST CDS_LIB standard
J 0
(-6375 5400);
DISPLAY INVISIBLE (-6375 5400);
FORCEPROP 1 LAST OFFPAGE TRUE
J 2
(-6700 5275);
DISPLAY 0.872340 (-6700 5275);
PAINT GREEN (-6700 5275);
DISPLAY INVISIBLE (-6700 5275);
FORCEPROP 1 LAST COMMENT_BODY TRUE
J 2
(-6475 5325);
DISPLAY 0.872340 (-6475 5325);
PAINT GREEN (-6475 5325);
DISPLAY INVISIBLE (-6475 5325);
FORCEPROP 2 LAST PATH I44
J 0
(-6175 5450);
DISPLAY 0.680851 (-6175 5450);
DISPLAY INVISIBLE (-6175 5450);
FORCEADD OFFPAGE..5
R 2
(-6375 5525);
FORCEPROP 2 LAST $XR0 310 
J 0
(-6186 5525);
DISPLAY 0.638298 (-6186 5525);
PAINT MONO (-6186 5525);
FORCEPROP 2 LAST CDS_LIB standard
J 0
(-6375 5525);
DISPLAY INVISIBLE (-6375 5525);
FORCEPROP 1 LAST OFFPAGE TRUE
J 2
(-6700 5400);
DISPLAY 0.872340 (-6700 5400);
PAINT GREEN (-6700 5400);
DISPLAY INVISIBLE (-6700 5400);
FORCEPROP 1 LAST COMMENT_BODY TRUE
J 2
(-6475 5450);
DISPLAY 0.872340 (-6475 5450);
PAINT GREEN (-6475 5450);
DISPLAY INVISIBLE (-6475 5450);
FORCEPROP 2 LAST PATH I45
J 0
(-6175 5575);
DISPLAY 0.680851 (-6175 5575);
DISPLAY INVISIBLE (-6175 5575);
FORCEADD OFFPAGE..5
R 2
(-6375 5575);
FORCEPROP 2 LAST $XR0 310 
J 0
(-6186 5575);
DISPLAY 0.638298 (-6186 5575);
PAINT MONO (-6186 5575);
FORCEPROP 2 LAST CDS_LIB standard
J 0
(-6375 5575);
DISPLAY INVISIBLE (-6375 5575);
FORCEPROP 1 LAST OFFPAGE TRUE
J 2
(-6700 5450);
DISPLAY 0.872340 (-6700 5450);
PAINT GREEN (-6700 5450);
DISPLAY INVISIBLE (-6700 5450);
FORCEPROP 1 LAST COMMENT_BODY TRUE
J 2
(-6475 5500);
DISPLAY 0.872340 (-6475 5500);
PAINT GREEN (-6475 5500);
DISPLAY INVISIBLE (-6475 5500);
FORCEPROP 2 LAST PATH I46
J 0
(-6175 5625);
DISPLAY 0.680851 (-6175 5625);
DISPLAY INVISIBLE (-6175 5625);
FORCEADD OFFPAGE..5
R 2
(-6375 5625);
FORCEPROP 2 LAST $XR0 310 
J 0
(-6186 5625);
DISPLAY 0.638298 (-6186 5625);
PAINT MONO (-6186 5625);
FORCEPROP 2 LAST CDS_LIB standard
J 0
(-6375 5625);
DISPLAY INVISIBLE (-6375 5625);
FORCEPROP 1 LAST OFFPAGE TRUE
J 2
(-6700 5500);
DISPLAY 0.872340 (-6700 5500);
PAINT GREEN (-6700 5500);
DISPLAY INVISIBLE (-6700 5500);
FORCEPROP 1 LAST COMMENT_BODY TRUE
J 2
(-6475 5550);
DISPLAY 0.872340 (-6475 5550);
PAINT GREEN (-6475 5550);
DISPLAY INVISIBLE (-6475 5550);
FORCEPROP 2 LAST PATH I47
J 0
(-6175 5675);
DISPLAY 0.680851 (-6175 5675);
DISPLAY INVISIBLE (-6175 5675);
FORCEADD OFFPAGE..5
R 2
(-6375 5700);
FORCEPROP 2 LAST $XR0 310 
J 0
(-6186 5700);
DISPLAY 0.638298 (-6186 5700);
PAINT MONO (-6186 5700);
FORCEPROP 2 LAST CDS_LIB standard
J 0
(-6375 5700);
DISPLAY INVISIBLE (-6375 5700);
FORCEPROP 1 LAST OFFPAGE TRUE
J 2
(-6700 5575);
DISPLAY 0.872340 (-6700 5575);
PAINT GREEN (-6700 5575);
DISPLAY INVISIBLE (-6700 5575);
FORCEPROP 1 LAST COMMENT_BODY TRUE
J 2
(-6475 5625);
DISPLAY 0.872340 (-6475 5625);
PAINT GREEN (-6475 5625);
DISPLAY INVISIBLE (-6475 5625);
FORCEPROP 2 LAST PATH I48
J 0
(-6175 5750);
DISPLAY 0.680851 (-6175 5750);
DISPLAY INVISIBLE (-6175 5750);
FORCEADD UNIVERSAL_GND..1
(-5025 5200);
FORCEPROP 3 LASTPIN (-5025 5250) SIG_NAME GND\g
J 0
(-5015 5260);
DISPLAY 0.659574 (-5015 5260);
PAINT MONO (-5015 5260);
DISPLAY INVISIBLE (-5015 5260);
FORCEPROP 2 LAST CDS_LIB pure_quanta_power
J 0
(-5025 5200);
DISPLAY INVISIBLE (-5025 5200);
FORCEPROP 1 LAST HDL_POWER GND
J 1
(-5000 5125);
DISPLAY 0.872340 (-5000 5125);
PAINT GREEN (-5000 5125);
DISPLAY INVISIBLE (-5000 5125);
FORCEPROP 1 LAST PATH I49
J 0
(-4950 5200);
DISPLAY 0.872340 (-4950 5200);
PAINT AQUA (-4950 5200);
DISPLAY INVISIBLE (-4950 5200);
FORCEADD Q_RES..2
(-8975 4125);
FORCEPROP 1 LAST LOCATION R1105
J 0
(-8930 4250);
DISPLAY 0.787234 (-8930 4250);
FORCEPROP 0 LAST $SEC 1
J 0
(-8925 4300);
DISPLAY 0.680851 (-8925 4300);
PAINT MONO (-8925 4300);
DISPLAY INVISIBLE (-8925 4300);
FORCEPROP 0 LAST CDS_SEC 1
J 0
(-8925 4300);
DISPLAY 0.680851 (-8925 4300);
DISPLAY INVISIBLE (-8925 4300);
FORCEPROP 1 LASTPIN (-8975 4225) $PN 1
J 0
(-8970 4187);
DISPLAY 0.787234 (-8970 4187);
PAINT MONO (-8970 4187);
FORCEPROP 1 LASTPIN (-8975 4025) $PN 2
J 0
(-8970 4035);
DISPLAY 0.787234 (-8970 4035);
PAINT MONO (-8970 4035);
FORCEPROP 1 LAST MATERIAL EMPTY
J 0
(-8935 4050);
DISPLAY 0.787234 (-8935 4050);
FORCEPROP 1 LAST VALUE 4.7K
J 0
(-8930 4200);
DISPLAY 0.787234 (-8930 4200);
FORCEPROP 1 LAST TOLERANCE 5%
J 0
(-8930 4150);
DISPLAY 0.787234 (-8930 4150);
FORCEPROP 1 LAST WATTAGE 1/20W
J 0
(-8935 4100);
DISPLAY 0.787234 (-8935 4100);
FORCEPROP 1 LAST PACK_TYPE 0201LF
J 0
(-8925 3975);
DISPLAY 0.787234 (-8925 3975);
FORCEPROP 2 LAST CDS_LIB pure_quanta
J 0
(-8975 4125);
DISPLAY INVISIBLE (-8975 4125);
FORCEPROP 1 LAST PATH I5
J 0
(-8925 4300);
DISPLAY 0.978723 (-8925 4300);
PAINT WHITE (-8925 4300);
DISPLAY INVISIBLE (-8925 4300);
FORCEPROP 1 LAST PART_NUMBER CS24701JE04
J 0
(-8935 4000);
DISPLAY 0.978723 (-8935 4000);
DISPLAY INVISIBLE (-8935 4000);
FORCEADD Q_RES..2
(-5025 5550);
FORCEPROP 1 LAST LOCATION R1091
J 0
(-4980 5675);
DISPLAY 0.787234 (-4980 5675);
FORCEPROP 0 LAST $SEC 1
J 0
(-4975 5725);
DISPLAY 0.680851 (-4975 5725);
PAINT MONO (-4975 5725);
DISPLAY INVISIBLE (-4975 5725);
FORCEPROP 0 LAST CDS_SEC 1
J 0
(-4975 5725);
DISPLAY 0.680851 (-4975 5725);
DISPLAY INVISIBLE (-4975 5725);
FORCEPROP 1 LASTPIN (-5025 5650) $PN 1
J 0
(-5020 5612);
DISPLAY 0.787234 (-5020 5612);
PAINT MONO (-5020 5612);
FORCEPROP 1 LASTPIN (-5025 5450) $PN 2
J 0
(-5020 5460);
DISPLAY 0.787234 (-5020 5460);
PAINT MONO (-5020 5460);
FORCEPROP 1 LAST PACK_TYPE 0201LF
J 0
(-4985 5375);
DISPLAY 0.787234 (-4985 5375);
FORCEPROP 1 LAST MATERIAL EMPTY
J 0
(-4985 5475);
DISPLAY 0.787234 (-4985 5475);
FORCEPROP 1 LAST WATTAGE 1/20W
J 0
(-4985 5525);
DISPLAY 0.787234 (-4985 5525);
FORCEPROP 1 LAST TOLERANCE 5%
J 0
(-4980 5575);
DISPLAY 0.787234 (-4980 5575);
FORCEPROP 1 LAST VALUE 4.7K
J 0
(-4980 5625);
DISPLAY 0.787234 (-4980 5625);
FORCEPROP 2 LAST CDS_LIB pure_quanta
J 0
(-5025 5550);
DISPLAY INVISIBLE (-5025 5550);
FORCEPROP 1 LAST PATH I50
J 0
(-4975 5725);
DISPLAY 0.978723 (-4975 5725);
PAINT WHITE (-4975 5725);
DISPLAY INVISIBLE (-4975 5725);
FORCEPROP 1 LAST PART_NUMBER CS24701JE04
J 0
(-4985 5425);
DISPLAY 0.787234 (-4985 5425);
DISPLAY INVISIBLE (-4985 5425);
FORCEADD Q_RES..2
(-5025 6075);
FORCEPROP 1 LAST LOCATION R1122
J 0
(-4980 6200);
DISPLAY 0.787234 (-4980 6200);
FORCEPROP 0 LAST $SEC 1
J 0
(-4975 6250);
DISPLAY 0.680851 (-4975 6250);
PAINT MONO (-4975 6250);
DISPLAY INVISIBLE (-4975 6250);
FORCEPROP 0 LAST CDS_SEC 1
J 0
(-4975 6250);
DISPLAY 0.680851 (-4975 6250);
DISPLAY INVISIBLE (-4975 6250);
FORCEPROP 1 LASTPIN (-5025 6175) $PN 1
J 0
(-5020 6137);
DISPLAY 0.787234 (-5020 6137);
PAINT MONO (-5020 6137);
FORCEPROP 1 LASTPIN (-5025 5975) $PN 2
J 0
(-5020 5985);
DISPLAY 0.787234 (-5020 5985);
PAINT MONO (-5020 5985);
FORCEPROP 1 LAST PACK_TYPE 0201LF
J 0
(-4985 5900);
DISPLAY 0.787234 (-4985 5900);
FORCEPROP 1 LAST WATTAGE 1/20W
J 0
(-4985 6050);
DISPLAY 0.787234 (-4985 6050);
FORCEPROP 1 LAST TOLERANCE 5%
J 0
(-4980 6100);
DISPLAY 0.787234 (-4980 6100);
FORCEPROP 1 LAST MATERIAL CHIP
J 0
(-4985 6000);
DISPLAY 0.787234 (-4985 6000);
FORCEPROP 1 LAST VALUE 4.7K
J 0
(-4980 6150);
DISPLAY 0.787234 (-4980 6150);
FORCEPROP 2 LAST CDS_LIB pure_quanta
J 0
(-5025 6075);
DISPLAY INVISIBLE (-5025 6075);
FORCEPROP 1 LAST PATH I51
J 0
(-4975 6250);
DISPLAY 0.978723 (-4975 6250);
PAINT WHITE (-4975 6250);
DISPLAY INVISIBLE (-4975 6250);
FORCEPROP 1 LAST PART_NUMBER CS24701JE04
J 0
(-4985 5950);
DISPLAY 0.787234 (-4985 5950);
DISPLAY INVISIBLE (-4985 5950);
FORCEADD OFFPAGE..5
R 2
(-4150 5800);
FORCEPROP 2 LAST $XR0 310 
J 0
(-3961 5800);
DISPLAY 0.638298 (-3961 5800);
PAINT MONO (-3961 5800);
FORCEPROP 2 LAST CDS_LIB standard
J 0
(-4150 5800);
DISPLAY INVISIBLE (-4150 5800);
FORCEPROP 1 LAST OFFPAGE TRUE
J 2
(-4475 5675);
DISPLAY 0.872340 (-4475 5675);
PAINT GREEN (-4475 5675);
DISPLAY INVISIBLE (-4475 5675);
FORCEPROP 1 LAST COMMENT_BODY TRUE
J 2
(-4250 5725);
DISPLAY 0.872340 (-4250 5725);
PAINT GREEN (-4250 5725);
DISPLAY INVISIBLE (-4250 5725);
FORCEPROP 2 LAST PATH I52
J 0
(-3950 5850);
DISPLAY 0.680851 (-3950 5850);
DISPLAY INVISIBLE (-3950 5850);
FORCEADD P1V0..1
(-5025 6400);
FORCEPROP 3 LASTPIN (-5025 6350) SIG_NAME P1V8_CPU0_RT_1D\g
J 0
(-5015 6360);
DISPLAY 0.659574 (-5015 6360);
PAINT MONO (-5015 6360);
DISPLAY INVISIBLE (-5015 6360);
FORCEPROP 1 LAST HDL_POWER P1V8_CPU0_RT_1D
J 1
(-5025 6450);
DISPLAY 0.489362 (-5025 6450);
PAINT SKYBLUE (-5025 6450);
FORCEPROP 2 LAST CDS_LIB pure_quanta_power
J 0
(-5025 6400);
DISPLAY INVISIBLE (-5025 6400);
FORCEPROP 1 LAST PATH I53
J 0
(-4975 6425);
DISPLAY 0.872340 (-4975 6425);
PAINT AQUA (-4975 6425);
DISPLAY INVISIBLE (-4975 6425);
FORCEADD UNIVERSAL_GND..1
R 1
(-2625 1700);
FORCEPROP 3 LASTPIN (-2675 1700) SIG_NAME GND\g
J 0
(-2665 1710);
DISPLAY 0.659574 (-2665 1710);
PAINT MONO (-2665 1710);
DISPLAY INVISIBLE (-2665 1710);
FORCEPROP 2 LAST CDS_LIB pure_quanta_power
J 0
(-2625 1700);
DISPLAY INVISIBLE (-2625 1700);
FORCEPROP 1 LAST HDL_POWER GND
R 1
J 1
(-2550 1725);
DISPLAY 0.872340 (-2550 1725);
PAINT GREEN (-2550 1725);
DISPLAY INVISIBLE (-2550 1725);
FORCEPROP 1 LAST PATH I54
R 1
J 0
(-2625 1775);
DISPLAY 0.872340 (-2625 1775);
PAINT AQUA (-2625 1775);
DISPLAY INVISIBLE (-2625 1775);
FORCEADD Q_RES..1
(-2575 2100);
FORCEPROP 1 LAST LOCATION R1096
J 0
(-2850 2100);
DISPLAY 0.978723 (-2850 2100);
FORCEPROP 0 LAST $SEC 1
J 0
(-2275 2150);
DISPLAY 0.680851 (-2275 2150);
PAINT MONO (-2275 2150);
DISPLAY INVISIBLE (-2275 2150);
FORCEPROP 0 LAST CDS_SEC 1
J 0
(-2275 2150);
DISPLAY 0.680851 (-2275 2150);
DISPLAY INVISIBLE (-2275 2150);
FORCEPROP 1 LASTPIN (-2675 2100) $PN 1
J 0
(-2663 2112);
DISPLAY 0.787234 (-2663 2112);
PAINT MONO (-2663 2112);
FORCEPROP 1 LASTPIN (-2475 2100) $PN 2
J 0
(-2513 2112);
DISPLAY 0.787234 (-2513 2112);
PAINT MONO (-2513 2112);
FORCEPROP 1 LAST PACK_TYPE 0201LF
J 0
(-2275 2100);
DISPLAY 0.787234 (-2275 2100);
FORCEPROP 1 LAST VALUE 0
J 2
(-2375 2100);
DISPLAY 0.787234 (-2375 2100);
FORCEPROP 2 LAST CDS_LIB pure_quanta
J 0
(-2575 2100);
DISPLAY INVISIBLE (-2575 2100);
FORCEPROP 1 LAST MATERIAL CHIP
J 0
(-2750 2175);
DISPLAY 0.787234 (-2750 2175);
DISPLAY INVISIBLE (-2750 2175);
FORCEPROP 1 LAST TOLERANCE 5%
J 0
(-2750 2225);
DISPLAY 0.787234 (-2750 2225);
DISPLAY INVISIBLE (-2750 2225);
FORCEPROP 1 LAST WATTAGE 1/20W
J 2
(-2775 2175);
DISPLAY 0.787234 (-2775 2175);
DISPLAY INVISIBLE (-2775 2175);
FORCEPROP 1 LAST PATH I55
J 0
(-2625 2250);
DISPLAY 0.978723 (-2625 2250);
PAINT WHITE (-2625 2250);
DISPLAY INVISIBLE (-2625 2250);
FORCEPROP 1 LAST PART_NUMBER CS00001JE10
J 0
(-2625 2225);
DISPLAY 0.808511 (-2625 2225);
DISPLAY INVISIBLE (-2625 2225);
FORCEADD Q_RES..1
(-2575 2200);
FORCEPROP 1 LAST LOCATION R1088
J 0
(-2850 2200);
DISPLAY 0.978723 (-2850 2200);
FORCEPROP 2 LAST SEC 1
J 0
(-2625 2400);
DISPLAY 0.680851 (-2625 2400);
PAINT MONO (-2625 2400);
DISPLAY INVISIBLE (-2625 2400);
FORCEPROP 1 LASTPIN (-2675 2200) $PN 1
J 0
(-2663 2212);
DISPLAY 0.787234 (-2663 2212);
PAINT MONO (-2663 2212);
FORCEPROP 1 LASTPIN (-2475 2200) $PN 2
J 0
(-2513 2212);
DISPLAY 0.787234 (-2513 2212);
PAINT MONO (-2513 2212);
FORCEPROP 1 LAST PACK_TYPE 0201LF
J 0
(-2275 2200);
DISPLAY 0.787234 (-2275 2200);
FORCEPROP 1 LAST VALUE 0
J 2
(-2375 2200);
DISPLAY 0.787234 (-2375 2200);
FORCEPROP 1 LAST WATTAGE 1/20W
J 2
(-2775 2275);
DISPLAY 0.787234 (-2775 2275);
DISPLAY INVISIBLE (-2775 2275);
FORCEPROP 1 LAST TOLERANCE 5%
J 0
(-2750 2325);
DISPLAY 0.787234 (-2750 2325);
DISPLAY INVISIBLE (-2750 2325);
FORCEPROP 1 LAST MATERIAL CHIP
J 0
(-2750 2275);
DISPLAY 0.787234 (-2750 2275);
DISPLAY INVISIBLE (-2750 2275);
FORCEPROP 2 LAST SEC_TYPE 0201LF
J 0
(-2625 2400);
DISPLAY 0.680851 (-2625 2400);
DISPLAY INVISIBLE (-2625 2400);
FORCEPROP 2 LAST CDS_LIB pure_quanta
J 0
(-2575 2200);
DISPLAY INVISIBLE (-2575 2200);
FORCEPROP 1 LAST PATH I56
J 0
(-2625 2350);
DISPLAY 0.978723 (-2625 2350);
PAINT WHITE (-2625 2350);
DISPLAY INVISIBLE (-2625 2350);
FORCEPROP 1 LAST PART_NUMBER CS00001JE10
J 0
(-2625 2325);
DISPLAY 0.808511 (-2625 2325);
DISPLAY INVISIBLE (-2625 2325);
FORCEADD OFFPAGE..1
R 2
(-2375 2600);
FORCEPROP 2 LAST $XR0 310 
J 0
(-2189 2600);
DISPLAY 0.638298 (-2189 2600);
PAINT MONO (-2189 2600);
FORCEPROP 2 LAST CDS_LIB standard
J 0
(-2375 2600);
DISPLAY INVISIBLE (-2375 2600);
FORCEPROP 1 LAST OFFPAGE TRUE
J 2
(-2700 2475);
DISPLAY 0.872340 (-2700 2475);
DISPLAY INVISIBLE (-2700 2475);
FORCEPROP 1 LAST COMMENT_BODY TRUE
J 2
(-2500 2500);
DISPLAY 0.872340 (-2500 2500);
PAINT GREEN (-2500 2500);
DISPLAY INVISIBLE (-2500 2500);
FORCEPROP 2 LAST PATH I58
J 0
(-2175 2650);
DISPLAY 0.680851 (-2175 2650);
DISPLAY INVISIBLE (-2175 2650);
FORCEADD OFFPAGE..1
R 2
(-2400 2800);
FORCEPROP 2 LAST $XR0 310 
J 0
(-2214 2800);
DISPLAY 0.638298 (-2214 2800);
PAINT MONO (-2214 2800);
FORCEPROP 2 LAST CDS_LIB standard
J 2
(-2400 2800);
DISPLAY INVISIBLE (-2400 2800);
FORCEPROP 1 LAST OFFPAGE TRUE
J 2
(-2725 2675);
DISPLAY 0.872340 (-2725 2675);
DISPLAY INVISIBLE (-2725 2675);
FORCEPROP 1 LAST COMMENT_BODY TRUE
J 2
(-2525 2700);
DISPLAY 0.872340 (-2525 2700);
PAINT GREEN (-2525 2700);
DISPLAY INVISIBLE (-2525 2700);
FORCEPROP 2 LAST PATH I59
J 0
(-2200 2850);
DISPLAY 0.680851 (-2200 2850);
DISPLAY INVISIBLE (-2200 2850);
FORCEADD P1V0..1
(-8975 4450);
FORCEPROP 3 LASTPIN (-8975 4400) SIG_NAME P1V8_CPU0_RT_1D\g
J 0
(-8965 4410);
DISPLAY 0.659574 (-8965 4410);
PAINT MONO (-8965 4410);
DISPLAY INVISIBLE (-8965 4410);
FORCEPROP 1 LAST HDL_POWER P1V8_CPU0_RT_1D
J 1
(-8975 4500);
DISPLAY 0.489362 (-8975 4500);
PAINT SKYBLUE (-8975 4500);
FORCEPROP 2 LAST CDS_LIB pure_quanta_power
J 0
(-8975 4450);
DISPLAY INVISIBLE (-8975 4450);
FORCEPROP 1 LAST PATH I6
J 0
(-8925 4475);
DISPLAY 0.872340 (-8925 4475);
PAINT AQUA (-8925 4475);
DISPLAY INVISIBLE (-8925 4475);
FORCEADD OFFPAGE..1
R 2
(-2475 3100);
FORCEPROP 2 LAST $XR0 310 
J 0
(-2289 3100);
DISPLAY 0.638298 (-2289 3100);
PAINT MONO (-2289 3100);
FORCEPROP 2 LAST CDS_LIB standard
J 0
(-2475 3100);
DISPLAY INVISIBLE (-2475 3100);
FORCEPROP 1 LAST OFFPAGE TRUE
J 2
(-2800 2975);
DISPLAY 0.872340 (-2800 2975);
DISPLAY INVISIBLE (-2800 2975);
FORCEPROP 1 LAST COMMENT_BODY TRUE
J 2
(-2600 3000);
DISPLAY 0.872340 (-2600 3000);
PAINT GREEN (-2600 3000);
DISPLAY INVISIBLE (-2600 3000);
FORCEPROP 2 LAST PATH I60
J 0
(-2275 3150);
DISPLAY 0.680851 (-2275 3150);
DISPLAY INVISIBLE (-2275 3150);
FORCEADD OFFPAGE..1
R 2
(-1050 2100);
FORCEPROP 2 LAST $XR1 310 
J 0
(-774 2100);
DISPLAY 0.638298 (-774 2100);
PAINT MONO (-774 2100);
FORCEPROP 2 LAST $XR0 81 
J 0
(-864 2100);
DISPLAY 0.638298 (-864 2100);
PAINT MONO (-864 2100);
FORCEPROP 2 LAST CDS_LIB standard
J 0
(-1050 2100);
DISPLAY INVISIBLE (-1050 2100);
FORCEPROP 1 LAST OFFPAGE TRUE
J 2
(-1375 1975);
DISPLAY 0.872340 (-1375 1975);
DISPLAY INVISIBLE (-1375 1975);
FORCEPROP 1 LAST COMMENT_BODY TRUE
J 2
(-1175 2000);
DISPLAY 0.872340 (-1175 2000);
PAINT GREEN (-1175 2000);
DISPLAY INVISIBLE (-1175 2000);
FORCEPROP 2 LAST PATH I62
J 0
(-750 2150);
DISPLAY 0.680851 (-750 2150);
DISPLAY INVISIBLE (-750 2150);
FORCEADD OFFPAGE..1
R 2
(-1050 2200);
FORCEPROP 2 LAST $XR1 310 
J 0
(-774 2200);
DISPLAY 0.638298 (-774 2200);
PAINT MONO (-774 2200);
FORCEPROP 2 LAST $XR0 81 
J 0
(-864 2200);
DISPLAY 0.638298 (-864 2200);
PAINT MONO (-864 2200);
FORCEPROP 2 LAST CDS_LIB standard
J 0
(-1050 2200);
DISPLAY INVISIBLE (-1050 2200);
FORCEPROP 1 LAST OFFPAGE TRUE
J 2
(-1375 2075);
DISPLAY 0.872340 (-1375 2075);
DISPLAY INVISIBLE (-1375 2075);
FORCEPROP 1 LAST COMMENT_BODY TRUE
J 2
(-1175 2100);
DISPLAY 0.872340 (-1175 2100);
PAINT GREEN (-1175 2100);
DISPLAY INVISIBLE (-1175 2100);
FORCEPROP 2 LAST PATH I63
J 0
(-750 2250);
DISPLAY 0.680851 (-750 2250);
DISPLAY INVISIBLE (-750 2250);
FORCEADD UNIVERSAL_GND..1
(-3475 4800);
FORCEPROP 3 LASTPIN (-3475 4850) SIG_NAME GND\g
J 0
(-3465 4860);
DISPLAY 0.659574 (-3465 4860);
PAINT MONO (-3465 4860);
DISPLAY INVISIBLE (-3465 4860);
FORCEPROP 2 LAST CDS_LIB pure_quanta_power
J 0
(-3475 4800);
DISPLAY INVISIBLE (-3475 4800);
FORCEPROP 1 LAST HDL_POWER GND
J 1
(-3450 4725);
DISPLAY 0.872340 (-3450 4725);
PAINT GREEN (-3450 4725);
DISPLAY INVISIBLE (-3450 4725);
FORCEPROP 1 LAST PATH I64
J 0
(-3400 4800);
DISPLAY 0.872340 (-3400 4800);
PAINT AQUA (-3400 4800);
DISPLAY INVISIBLE (-3400 4800);
FORCEADD Q_RES..2
(-3475 5225);
FORCEPROP 1 LAST LOCATION R1098
J 0
(-3430 5350);
DISPLAY 0.787234 (-3430 5350);
FORCEPROP 0 LAST $SEC 1
J 0
(-3425 5400);
DISPLAY 0.680851 (-3425 5400);
PAINT MONO (-3425 5400);
DISPLAY INVISIBLE (-3425 5400);
FORCEPROP 0 LAST CDS_SEC 1
J 0
(-3425 5400);
DISPLAY 0.680851 (-3425 5400);
DISPLAY INVISIBLE (-3425 5400);
FORCEPROP 1 LASTPIN (-3475 5325) $PN 1
J 0
(-3470 5287);
DISPLAY 0.787234 (-3470 5287);
PAINT MONO (-3470 5287);
FORCEPROP 1 LASTPIN (-3475 5125) $PN 2
J 0
(-3470 5135);
DISPLAY 0.787234 (-3470 5135);
PAINT MONO (-3470 5135);
FORCEPROP 1 LAST MATERIAL EMPTY
J 0
(-3435 5150);
DISPLAY 0.787234 (-3435 5150);
FORCEPROP 1 LAST WATTAGE 1/20W
J 0
(-3435 5200);
DISPLAY 0.787234 (-3435 5200);
FORCEPROP 1 LAST PACK_TYPE 0201LF
J 0
(-3435 5050);
DISPLAY 0.787234 (-3435 5050);
FORCEPROP 1 LAST VALUE 1K
J 0
(-3430 5300);
DISPLAY 0.787234 (-3430 5300);
FORCEPROP 1 LAST TOLERANCE 1%
J 0
(-3430 5250);
DISPLAY 0.787234 (-3430 5250);
FORCEPROP 2 LAST CDS_LIB pure_quanta
J 0
(-3475 5225);
DISPLAY INVISIBLE (-3475 5225);
FORCEPROP 1 LAST PATH I65
J 0
(-3425 5400);
DISPLAY 0.978723 (-3425 5400);
PAINT WHITE (-3425 5400);
DISPLAY INVISIBLE (-3425 5400);
FORCEPROP 1 LAST PART_NUMBER CS21001FE07
J 0
(-3435 5100);
DISPLAY 0.978723 (-3435 5100);
DISPLAY INVISIBLE (-3435 5100);
FORCEADD Q_RES..2
(-3175 5225);
FORCEPROP 1 LAST LOCATION R1100
J 0
(-3130 5350);
DISPLAY 0.787234 (-3130 5350);
FORCEPROP 0 LAST $SEC 1
J 0
(-3125 5400);
DISPLAY 0.680851 (-3125 5400);
PAINT MONO (-3125 5400);
DISPLAY INVISIBLE (-3125 5400);
FORCEPROP 0 LAST CDS_SEC 1
J 0
(-3125 5400);
DISPLAY 0.680851 (-3125 5400);
DISPLAY INVISIBLE (-3125 5400);
FORCEPROP 1 LASTPIN (-3175 5325) $PN 1
J 0
(-3170 5287);
DISPLAY 0.787234 (-3170 5287);
PAINT MONO (-3170 5287);
FORCEPROP 1 LASTPIN (-3175 5125) $PN 2
J 0
(-3170 5135);
DISPLAY 0.787234 (-3170 5135);
PAINT MONO (-3170 5135);
FORCEPROP 1 LAST MATERIAL CHIP
J 0
(-3135 5150);
DISPLAY 0.787234 (-3135 5150);
FORCEPROP 1 LAST WATTAGE 1/20W
J 0
(-3135 5200);
DISPLAY 0.787234 (-3135 5200);
FORCEPROP 1 LAST VALUE 20K
J 0
(-3130 5300);
DISPLAY 0.787234 (-3130 5300);
FORCEPROP 1 LAST TOLERANCE 1%
J 0
(-3130 5250);
DISPLAY 0.787234 (-3130 5250);
FORCEPROP 1 LAST PACK_TYPE 0201LF
J 0
(-3135 5050);
DISPLAY 0.787234 (-3135 5050);
FORCEPROP 2 LAST CDS_LIB pure_quanta
J 0
(-3175 5225);
DISPLAY INVISIBLE (-3175 5225);
FORCEPROP 1 LAST PATH I66
J 0
(-3125 5400);
DISPLAY 0.978723 (-3125 5400);
PAINT WHITE (-3125 5400);
DISPLAY INVISIBLE (-3125 5400);
FORCEPROP 1 LAST PART_NUMBER CS32001FE00
J 0
(-3135 5100);
DISPLAY 0.978723 (-3135 5100);
DISPLAY INVISIBLE (-3135 5100);
FORCEADD Q_RES..2
(-3475 6000);
FORCEPROP 1 LAST LOCATION R1097
J 0
(-3430 6125);
DISPLAY 0.787234 (-3430 6125);
FORCEPROP 0 LAST $SEC 1
J 0
(-3425 6175);
DISPLAY 0.680851 (-3425 6175);
PAINT MONO (-3425 6175);
DISPLAY INVISIBLE (-3425 6175);
FORCEPROP 0 LAST CDS_SEC 1
J 0
(-3425 6175);
DISPLAY 0.680851 (-3425 6175);
DISPLAY INVISIBLE (-3425 6175);
FORCEPROP 1 LASTPIN (-3475 6100) $PN 1
J 0
(-3470 6062);
DISPLAY 0.787234 (-3470 6062);
PAINT MONO (-3470 6062);
FORCEPROP 1 LASTPIN (-3475 5900) $PN 2
J 0
(-3470 5910);
DISPLAY 0.787234 (-3470 5910);
PAINT MONO (-3470 5910);
FORCEPROP 1 LAST VALUE 1K
J 0
(-3430 6075);
DISPLAY 0.787234 (-3430 6075);
FORCEPROP 1 LAST PACK_TYPE 0201LF
J 0
(-3435 5825);
DISPLAY 0.787234 (-3435 5825);
FORCEPROP 1 LAST MATERIAL CHIP
J 0
(-3435 5925);
DISPLAY 0.787234 (-3435 5925);
FORCEPROP 1 LAST WATTAGE 1/20W
J 0
(-3435 5975);
DISPLAY 0.787234 (-3435 5975);
FORCEPROP 1 LAST TOLERANCE 1%
J 0
(-3430 6025);
DISPLAY 0.787234 (-3430 6025);
FORCEPROP 2 LAST CDS_LIB pure_quanta
J 0
(-3475 6000);
DISPLAY INVISIBLE (-3475 6000);
FORCEPROP 1 LAST PATH I67
J 0
(-3425 6175);
DISPLAY 0.978723 (-3425 6175);
PAINT WHITE (-3425 6175);
DISPLAY INVISIBLE (-3425 6175);
FORCEPROP 1 LAST PART_NUMBER CS21001FE07
J 0
(-3435 5875);
DISPLAY 0.978723 (-3435 5875);
DISPLAY INVISIBLE (-3435 5875);
FORCEADD Q_RES..2
(-3175 6000);
FORCEPROP 1 LAST LOCATION R1099
J 0
(-3130 6125);
DISPLAY 0.978723 (-3130 6125);
FORCEPROP 0 LAST $SEC 1
J 0
(-3125 6175);
DISPLAY 0.680851 (-3125 6175);
PAINT MONO (-3125 6175);
DISPLAY INVISIBLE (-3125 6175);
FORCEPROP 0 LAST CDS_SEC 1
J 0
(-3125 6175);
DISPLAY 0.680851 (-3125 6175);
DISPLAY INVISIBLE (-3125 6175);
FORCEPROP 1 LASTPIN (-3175 6100) $PN 1
J 0
(-3170 6062);
DISPLAY 0.787234 (-3170 6062);
PAINT MONO (-3170 6062);
FORCEPROP 1 LASTPIN (-3175 5900) $PN 2
J 0
(-3170 5910);
DISPLAY 0.787234 (-3170 5910);
PAINT MONO (-3170 5910);
FORCEPROP 1 LAST TOLERANCE 1%
J 0
(-3130 6025);
DISPLAY 0.787234 (-3130 6025);
FORCEPROP 1 LAST VALUE 1K
J 0
(-3130 6075);
DISPLAY 0.787234 (-3130 6075);
FORCEPROP 1 LAST WATTAGE 1/20W
J 0
(-3135 5975);
DISPLAY 0.787234 (-3135 5975);
FORCEPROP 1 LAST PACK_TYPE 0201LF
J 0
(-3135 5825);
DISPLAY 0.787234 (-3135 5825);
FORCEPROP 1 LAST MATERIAL EMPTY
J 0
(-3135 5925);
DISPLAY 0.787234 (-3135 5925);
FORCEPROP 2 LAST CDS_LIB pure_quanta
J 0
(-3175 6000);
DISPLAY INVISIBLE (-3175 6000);
FORCEPROP 1 LAST PATH I68
J 0
(-3125 6175);
DISPLAY 0.978723 (-3125 6175);
PAINT WHITE (-3125 6175);
DISPLAY INVISIBLE (-3125 6175);
FORCEPROP 1 LAST PART_NUMBER CS21001FE07
J 0
(-3135 5875);
DISPLAY 0.978723 (-3135 5875);
DISPLAY INVISIBLE (-3135 5875);
FORCEADD Q_RES..2
(-2825 5225);
FORCEPROP 1 LAST LOCATION R1102
J 0
(-2780 5350);
DISPLAY 0.978723 (-2780 5350);
FORCEPROP 0 LAST $SEC 1
J 0
(-2775 5400);
DISPLAY 0.680851 (-2775 5400);
PAINT MONO (-2775 5400);
DISPLAY INVISIBLE (-2775 5400);
FORCEPROP 0 LAST CDS_SEC 1
J 0
(-2775 5400);
DISPLAY 0.680851 (-2775 5400);
DISPLAY INVISIBLE (-2775 5400);
FORCEPROP 1 LASTPIN (-2825 5325) $PN 1
J 0
(-2820 5287);
DISPLAY 0.787234 (-2820 5287);
PAINT MONO (-2820 5287);
FORCEPROP 1 LASTPIN (-2825 5125) $PN 2
J 0
(-2820 5135);
DISPLAY 0.787234 (-2820 5135);
PAINT MONO (-2820 5135);
FORCEPROP 1 LAST PACK_TYPE 0201LF
J 0
(-2785 5050);
DISPLAY 0.787234 (-2785 5050);
FORCEPROP 1 LAST WATTAGE 1/20W
J 0
(-2785 5200);
DISPLAY 0.787234 (-2785 5200);
FORCEPROP 1 LAST TOLERANCE 1%
J 0
(-2780 5250);
DISPLAY 0.787234 (-2780 5250);
FORCEPROP 1 LAST VALUE 1K
J 0
(-2780 5300);
DISPLAY 0.787234 (-2780 5300);
FORCEPROP 1 LAST MATERIAL CHIP
J 0
(-2785 5150);
DISPLAY 0.787234 (-2785 5150);
FORCEPROP 2 LAST CDS_LIB pure_quanta
J 0
(-2825 5225);
DISPLAY INVISIBLE (-2825 5225);
FORCEPROP 1 LAST PATH I69
J 0
(-2775 5400);
DISPLAY 0.978723 (-2775 5400);
PAINT WHITE (-2775 5400);
DISPLAY INVISIBLE (-2775 5400);
FORCEPROP 1 LAST PART_NUMBER CS21001FE07
J 0
(-2785 5100);
DISPLAY 0.978723 (-2785 5100);
DISPLAY INVISIBLE (-2785 5100);
FORCEADD Q_RES..2
(-8950 5050);
FORCEPROP 1 LAST LOCATION R1112
J 0
(-8905 5175);
DISPLAY 0.787234 (-8905 5175);
FORCEPROP 0 LAST $SEC 1
J 0
(-8900 5225);
DISPLAY 0.680851 (-8900 5225);
PAINT MONO (-8900 5225);
DISPLAY INVISIBLE (-8900 5225);
FORCEPROP 0 LAST CDS_SEC 1
J 0
(-8900 5225);
DISPLAY 0.680851 (-8900 5225);
DISPLAY INVISIBLE (-8900 5225);
FORCEPROP 1 LASTPIN (-8950 5150) $PN 1
J 0
(-8945 5112);
DISPLAY 0.787234 (-8945 5112);
PAINT MONO (-8945 5112);
FORCEPROP 1 LASTPIN (-8950 4950) $PN 2
J 0
(-8945 4960);
DISPLAY 0.787234 (-8945 4960);
PAINT MONO (-8945 4960);
FORCEPROP 1 LAST VALUE 10K
J 0
(-8905 5125);
DISPLAY 0.787234 (-8905 5125);
FORCEPROP 1 LAST TOLERANCE 1%
J 0
(-8905 5075);
DISPLAY 0.787234 (-8905 5075);
FORCEPROP 1 LAST WATTAGE 1/20W
J 0
(-8910 5025);
DISPLAY 0.787234 (-8910 5025);
FORCEPROP 1 LAST MATERIAL CHIP
J 0
(-8910 4975);
DISPLAY 0.787234 (-8910 4975);
FORCEPROP 1 LAST PACK_TYPE 0201LF
J 0
(-8910 4875);
DISPLAY 0.787234 (-8910 4875);
FORCEPROP 2 LAST CDS_LIB pure_quanta
J 0
(-8950 5050);
DISPLAY INVISIBLE (-8950 5050);
FORCEPROP 1 LAST PATH I7
J 0
(-8900 5225);
DISPLAY 0.978723 (-8900 5225);
PAINT WHITE (-8900 5225);
DISPLAY INVISIBLE (-8900 5225);
FORCEPROP 1 LAST PART_NUMBER CS31001FE17
J 0
(-8910 4925);
DISPLAY 0.638298 (-8910 4925);
DISPLAY INVISIBLE (-8910 4925);
FORCEADD Q_RES..2
(-2825 5975);
FORCEPROP 1 LAST LOCATION R1101
J 0
(-2780 6100);
DISPLAY 0.978723 (-2780 6100);
FORCEPROP 0 LAST $SEC 1
J 0
(-2775 6150);
DISPLAY 0.680851 (-2775 6150);
PAINT MONO (-2775 6150);
DISPLAY INVISIBLE (-2775 6150);
FORCEPROP 0 LAST CDS_SEC 1
J 0
(-2775 6150);
DISPLAY 0.680851 (-2775 6150);
DISPLAY INVISIBLE (-2775 6150);
FORCEPROP 1 LASTPIN (-2825 6075) $PN 1
J 0
(-2820 6037);
DISPLAY 0.787234 (-2820 6037);
PAINT MONO (-2820 6037);
FORCEPROP 1 LASTPIN (-2825 5875) $PN 2
J 0
(-2820 5885);
DISPLAY 0.787234 (-2820 5885);
PAINT MONO (-2820 5885);
FORCEPROP 1 LAST WATTAGE 1/20W
J 0
(-2785 5950);
DISPLAY 0.787234 (-2785 5950);
FORCEPROP 1 LAST TOLERANCE 1%
J 0
(-2780 6000);
DISPLAY 0.787234 (-2780 6000);
FORCEPROP 1 LAST PACK_TYPE 0201LF
J 0
(-2785 5800);
DISPLAY 0.787234 (-2785 5800);
FORCEPROP 1 LAST VALUE 1K
J 0
(-2780 6050);
DISPLAY 0.787234 (-2780 6050);
FORCEPROP 1 LAST MATERIAL EMPTY
J 0
(-2785 5900);
DISPLAY 0.787234 (-2785 5900);
FORCEPROP 2 LAST CDS_LIB pure_quanta
J 0
(-2825 5975);
DISPLAY INVISIBLE (-2825 5975);
FORCEPROP 1 LAST PATH I70
J 0
(-2775 6150);
DISPLAY 0.978723 (-2775 6150);
PAINT WHITE (-2775 6150);
DISPLAY INVISIBLE (-2775 6150);
FORCEPROP 1 LAST PART_NUMBER CS21001FE07
J 0
(-2785 5850);
DISPLAY 0.978723 (-2785 5850);
DISPLAY INVISIBLE (-2785 5850);
FORCEADD P1V0..1
(-3475 6425);
FORCEPROP 3 LASTPIN (-3475 6375) SIG_NAME P1V8_CPU0_RT_1D\g
J 0
(-3465 6385);
DISPLAY 0.659574 (-3465 6385);
PAINT MONO (-3465 6385);
DISPLAY INVISIBLE (-3465 6385);
FORCEPROP 1 LAST HDL_POWER P1V8_CPU0_RT_1D
J 1
(-3475 6475);
DISPLAY 0.489362 (-3475 6475);
PAINT SKYBLUE (-3475 6475);
FORCEPROP 2 LAST CDS_LIB pure_quanta_power
J 0
(-3475 6425);
DISPLAY INVISIBLE (-3475 6425);
FORCEPROP 1 LAST PATH I71
J 0
(-3425 6450);
DISPLAY 0.872340 (-3425 6450);
PAINT AQUA (-3425 6450);
DISPLAY INVISIBLE (-3425 6450);
FORCEADD GND..1
(-1475 4850);
FORCEPROP 3 LASTPIN (-1475 4900) SIG_NAME GND\g
J 0
(-1465 4910);
DISPLAY 0.659574 (-1465 4910);
PAINT MONO (-1465 4910);
DISPLAY INVISIBLE (-1465 4910);
FORCEPROP 2 LAST BOM_COST MEM
J 0
(-1575 4925);
DISPLAY 0.808511 (-1575 4925);
DISPLAY INVISIBLE (-1575 4925);
FORCEPROP 1 LAST SIZE 1B
J 0
(-1400 4800);
DISPLAY 0.851064 (-1400 4800);
PAINT GREEN (-1400 4800);
DISPLAY INVISIBLE (-1400 4800);
FORCEPROP 2 LAST CDS_LIB pure_quanta_power
J 0
(-1475 4850);
DISPLAY INVISIBLE (-1475 4850);
FORCEPROP 1 LAST HDL_POWER GND
J 0
(-1475 5000);
DISPLAY 0.851064 (-1475 5000);
PAINT GREEN (-1475 5000);
DISPLAY INVISIBLE (-1475 5000);
FORCEPROP 1 LAST PATH I72
J 0
(-1400 4850);
DISPLAY 0.872340 (-1400 4850);
PAINT AQUA (-1400 4850);
DISPLAY INVISIBLE (-1400 4850);
FORCEADD GND..1
(-1300 4875);
FORCEPROP 3 LASTPIN (-1300 4925) SIG_NAME GND\g
J 0
(-1290 4935);
DISPLAY 0.659574 (-1290 4935);
PAINT MONO (-1290 4935);
DISPLAY INVISIBLE (-1290 4935);
FORCEPROP 2 LAST CDS_LIB pure_quanta_power
J 0
(-1300 4875);
DISPLAY INVISIBLE (-1300 4875);
FORCEPROP 2 LAST BOM_COST MEM
J 0
(-1400 4950);
DISPLAY 0.808511 (-1400 4950);
DISPLAY INVISIBLE (-1400 4950);
FORCEPROP 1 LAST SIZE 1B
J 0
(-1225 4825);
DISPLAY 0.851064 (-1225 4825);
PAINT GREEN (-1225 4825);
DISPLAY INVISIBLE (-1225 4825);
FORCEPROP 1 LAST HDL_POWER GND
J 0
(-1300 5025);
DISPLAY 0.851064 (-1300 5025);
PAINT GREEN (-1300 5025);
DISPLAY INVISIBLE (-1300 5025);
FORCEPROP 1 LAST PATH I73
J 0
(-1225 4875);
DISPLAY 0.872340 (-1225 4875);
PAINT AQUA (-1225 4875);
DISPLAY INVISIBLE (-1225 4875);
FORCEADD Q_RES..2
(-1300 5225);
FORCEPROP 1 LAST LOCATION R1103
J 0
(-1255 5350);
DISPLAY 0.638298 (-1255 5350);
FORCEPROP 0 LAST $SEC 1
J 0
(-1250 5400);
DISPLAY 0.680851 (-1250 5400);
PAINT MONO (-1250 5400);
DISPLAY INVISIBLE (-1250 5400);
FORCEPROP 0 LAST CDS_SEC 1
J 0
(-1250 5400);
DISPLAY 0.680851 (-1250 5400);
DISPLAY INVISIBLE (-1250 5400);
FORCEPROP 1 LASTPIN (-1300 5325) $PN 1
J 0
(-1295 5287);
DISPLAY 0.787234 (-1295 5287);
PAINT MONO (-1295 5287);
FORCEPROP 1 LASTPIN (-1300 5125) $PN 2
J 0
(-1295 5135);
DISPLAY 0.787234 (-1295 5135);
PAINT MONO (-1295 5135);
FORCEPROP 1 LAST VALUE 10K
J 0
(-1255 5300);
DISPLAY 0.638298 (-1255 5300);
FORCEPROP 1 LAST TOLERANCE 1%
J 0
(-1255 5250);
DISPLAY 0.638298 (-1255 5250);
FORCEPROP 1 LAST WATTAGE 1/20W
J 0
(-1260 5200);
DISPLAY 0.638298 (-1260 5200);
FORCEPROP 1 LAST MATERIAL CHIP
J 0
(-1260 5150);
DISPLAY 0.638298 (-1260 5150);
FORCEPROP 1 LAST PACK_TYPE 0201LF
J 0
(-1260 5050);
DISPLAY 0.638298 (-1260 5050);
FORCEPROP 2 LAST CDS_LIB pure_quanta
J 0
(-1300 5225);
DISPLAY INVISIBLE (-1300 5225);
FORCEPROP 1 LAST PATH I74
J 0
(-1250 5400);
DISPLAY 0.978723 (-1250 5400);
PAINT WHITE (-1250 5400);
DISPLAY INVISIBLE (-1250 5400);
FORCEPROP 1 LAST PART_NUMBER CS31001FE17
J 0
(-1260 5100);
DISPLAY 0.638298 (-1260 5100);
DISPLAY INVISIBLE (-1260 5100);
FORCEADD Q_RES..2
R 2
(-1475 5225);
FORCEPROP 1 LAST LOCATION R1104
J 2
(-1520 5350);
DISPLAY 0.638298 (-1520 5350);
FORCEPROP 0 LAST $SEC 1
J 0
(-1500 5400);
DISPLAY 0.680851 (-1500 5400);
PAINT MONO (-1500 5400);
DISPLAY INVISIBLE (-1500 5400);
FORCEPROP 0 LAST CDS_SEC 1
J 0
(-1500 5400);
DISPLAY 0.680851 (-1500 5400);
DISPLAY INVISIBLE (-1500 5400);
FORCEPROP 1 LASTPIN (-1475 5325) $PN 1
J 2
(-1480 5287);
DISPLAY 0.787234 (-1480 5287);
PAINT MONO (-1480 5287);
FORCEPROP 1 LASTPIN (-1475 5125) $PN 2
J 2
(-1480 5135);
DISPLAY 0.787234 (-1480 5135);
PAINT MONO (-1480 5135);
FORCEPROP 1 LAST TOLERANCE 1%
J 2
(-1520 5250);
DISPLAY 0.638298 (-1520 5250);
FORCEPROP 1 LAST WATTAGE 1/20W
J 2
(-1515 5200);
DISPLAY 0.638298 (-1515 5200);
FORCEPROP 1 LAST VALUE 10K
J 2
(-1520 5300);
DISPLAY 0.638298 (-1520 5300);
FORCEPROP 1 LAST MATERIAL CHIP
J 2
(-1515 5150);
DISPLAY 0.638298 (-1515 5150);
FORCEPROP 1 LAST PACK_TYPE 0201LF
J 2
(-1515 5050);
DISPLAY 0.638298 (-1515 5050);
FORCEPROP 2 LAST CDS_LIB pure_quanta
J 2
(-1475 5225);
DISPLAY INVISIBLE (-1475 5225);
FORCEPROP 1 LAST PATH I75
J 2
(-1525 5400);
DISPLAY 0.978723 (-1525 5400);
PAINT WHITE (-1525 5400);
DISPLAY INVISIBLE (-1525 5400);
FORCEPROP 1 LAST PART_NUMBER CS31001FE17
J 2
(-1515 5100);
DISPLAY 0.638298 (-1515 5100);
DISPLAY INVISIBLE (-1515 5100);
FORCEADD OFFPAGE..5
R 2
(-1925 5475);
FORCEPROP 2 LAST $XR0 310 
J 0
(-1736 5475);
DISPLAY 0.638298 (-1736 5475);
PAINT MONO (-1736 5475);
FORCEPROP 2 LAST CDS_LIB standard
J 0
(-1925 5475);
DISPLAY INVISIBLE (-1925 5475);
FORCEPROP 1 LAST OFFPAGE TRUE
J 2
(-2250 5350);
DISPLAY 0.872340 (-2250 5350);
PAINT GREEN (-2250 5350);
DISPLAY INVISIBLE (-2250 5350);
FORCEPROP 1 LAST COMMENT_BODY TRUE
J 2
(-2025 5400);
DISPLAY 0.872340 (-2025 5400);
PAINT GREEN (-2025 5400);
DISPLAY INVISIBLE (-2025 5400);
FORCEPROP 2 LAST PATH I76
J 0
(-1725 5525);
DISPLAY 0.680851 (-1725 5525);
DISPLAY INVISIBLE (-1725 5525);
FORCEADD OFFPAGE..5
R 2
(-1925 5575);
FORCEPROP 2 LAST $XR0 310 
J 0
(-1736 5575);
DISPLAY 0.638298 (-1736 5575);
PAINT MONO (-1736 5575);
FORCEPROP 2 LAST CDS_LIB standard
J 0
(-1925 5575);
DISPLAY INVISIBLE (-1925 5575);
FORCEPROP 1 LAST OFFPAGE TRUE
J 2
(-2250 5450);
DISPLAY 0.872340 (-2250 5450);
PAINT GREEN (-2250 5450);
DISPLAY INVISIBLE (-2250 5450);
FORCEPROP 1 LAST COMMENT_BODY TRUE
J 2
(-2025 5500);
DISPLAY 0.872340 (-2025 5500);
PAINT GREEN (-2025 5500);
DISPLAY INVISIBLE (-2025 5500);
FORCEPROP 2 LAST PATH I77
J 0
(-1725 5625);
DISPLAY 0.680851 (-1725 5625);
DISPLAY INVISIBLE (-1725 5625);
FORCEADD OFFPAGE..5
R 2
(-1925 5675);
FORCEPROP 2 LAST $XR0 310 
J 0
(-1736 5675);
DISPLAY 0.638298 (-1736 5675);
PAINT MONO (-1736 5675);
FORCEPROP 2 LAST CDS_LIB standard
J 0
(-1925 5675);
DISPLAY INVISIBLE (-1925 5675);
FORCEPROP 1 LAST OFFPAGE TRUE
J 2
(-2250 5550);
DISPLAY 0.872340 (-2250 5550);
PAINT GREEN (-2250 5550);
DISPLAY INVISIBLE (-2250 5550);
FORCEPROP 1 LAST COMMENT_BODY TRUE
J 2
(-2025 5600);
DISPLAY 0.872340 (-2025 5600);
PAINT GREEN (-2025 5600);
DISPLAY INVISIBLE (-2025 5600);
FORCEPROP 2 LAST PATH I78
J 0
(-1725 5725);
DISPLAY 0.680851 (-1725 5725);
DISPLAY INVISIBLE (-1725 5725);
FORCEADD Q_RES..2
R 2
(-1475 6050);
FORCEPROP 1 LAST LOCATION R1107
J 2
(-1520 6175);
DISPLAY 0.787234 (-1520 6175);
FORCEPROP 0 LAST $SEC 1
J 0
(-1500 6225);
DISPLAY 0.680851 (-1500 6225);
PAINT MONO (-1500 6225);
DISPLAY INVISIBLE (-1500 6225);
FORCEPROP 0 LAST CDS_SEC 1
J 0
(-1500 6225);
DISPLAY 0.680851 (-1500 6225);
DISPLAY INVISIBLE (-1500 6225);
FORCEPROP 1 LASTPIN (-1475 6150) $PN 1
J 2
(-1480 6112);
DISPLAY 0.787234 (-1480 6112);
PAINT MONO (-1480 6112);
FORCEPROP 1 LASTPIN (-1475 5950) $PN 2
J 2
(-1480 5960);
DISPLAY 0.787234 (-1480 5960);
PAINT MONO (-1480 5960);
FORCEPROP 1 LAST PACK_TYPE 0201LF
J 2
(-1525 5900);
DISPLAY 0.787234 (-1525 5900);
FORCEPROP 1 LAST MATERIAL EMPTY
J 2
(-1515 5975);
DISPLAY 0.787234 (-1515 5975);
FORCEPROP 1 LAST VALUE 4.7K
J 2
(-1520 6125);
DISPLAY 0.787234 (-1520 6125);
FORCEPROP 1 LAST TOLERANCE 5%
J 2
(-1520 6075);
DISPLAY 0.787234 (-1520 6075);
FORCEPROP 1 LAST WATTAGE 1/20W
J 2
(-1515 6025);
DISPLAY 0.787234 (-1515 6025);
FORCEPROP 2 LAST CDS_LIB pure_quanta
J 2
(-1475 6050);
DISPLAY INVISIBLE (-1475 6050);
FORCEPROP 1 LAST PATH I79
J 2
(-1525 6225);
DISPLAY 0.978723 (-1525 6225);
PAINT WHITE (-1525 6225);
DISPLAY INVISIBLE (-1525 6225);
FORCEPROP 1 LAST PART_NUMBER CS24701JE04
J 2
(-1515 5925);
DISPLAY 0.978723 (-1515 5925);
DISPLAY INVISIBLE (-1515 5925);
FORCEADD Q_RES..2
(-8650 5050);
FORCEPROP 1 LAST LOCATION R1113
J 0
(-8605 5175);
DISPLAY 0.787234 (-8605 5175);
FORCEPROP 0 LAST $SEC 1
J 0
(-8600 5225);
DISPLAY 0.680851 (-8600 5225);
PAINT MONO (-8600 5225);
DISPLAY INVISIBLE (-8600 5225);
FORCEPROP 0 LAST CDS_SEC 1
J 0
(-8600 5225);
DISPLAY 0.680851 (-8600 5225);
DISPLAY INVISIBLE (-8600 5225);
FORCEPROP 1 LASTPIN (-8650 5150) $PN 1
J 0
(-8645 5112);
DISPLAY 0.787234 (-8645 5112);
PAINT MONO (-8645 5112);
FORCEPROP 1 LASTPIN (-8650 4950) $PN 2
J 0
(-8645 4960);
DISPLAY 0.787234 (-8645 4960);
PAINT MONO (-8645 4960);
FORCEPROP 1 LAST WATTAGE 1/20W
J 0
(-8610 5025);
DISPLAY 0.787234 (-8610 5025);
FORCEPROP 1 LAST MATERIAL CHIP
J 0
(-8610 4975);
DISPLAY 0.787234 (-8610 4975);
FORCEPROP 1 LAST TOLERANCE 1%
J 0
(-8605 5075);
DISPLAY 0.787234 (-8605 5075);
FORCEPROP 1 LAST VALUE 10K
J 0
(-8605 5125);
DISPLAY 0.787234 (-8605 5125);
FORCEPROP 1 LAST PACK_TYPE 0201LF
J 0
(-8610 4875);
DISPLAY 0.787234 (-8610 4875);
FORCEPROP 2 LAST CDS_LIB pure_quanta
J 0
(-8650 5050);
DISPLAY INVISIBLE (-8650 5050);
FORCEPROP 1 LAST PATH I8
J 0
(-8600 5225);
DISPLAY 0.978723 (-8600 5225);
PAINT WHITE (-8600 5225);
DISPLAY INVISIBLE (-8600 5225);
FORCEPROP 1 LAST PART_NUMBER CS31001FE17
J 0
(-8610 4925);
DISPLAY 0.510638 (-8610 4925);
DISPLAY INVISIBLE (-8610 4925);
FORCEADD OFFPAGE..1
R 2
(-525 5450);
FORCEPROP 2 LAST $XR1 310 
J 0
(-249 5450);
DISPLAY 0.638298 (-249 5450);
PAINT MONO (-249 5450);
FORCEPROP 2 LAST $XR0 81 
J 0
(-339 5450);
DISPLAY 0.638298 (-339 5450);
PAINT MONO (-339 5450);
FORCEPROP 2 LAST CDS_LIB standard
J 0
(-525 5450);
DISPLAY INVISIBLE (-525 5450);
FORCEPROP 1 LAST OFFPAGE TRUE
J 2
(-850 5325);
DISPLAY 0.872340 (-850 5325);
PAINT GREEN (-850 5325);
DISPLAY INVISIBLE (-850 5325);
FORCEPROP 1 LAST COMMENT_BODY TRUE
J 2
(-650 5350);
DISPLAY 0.872340 (-650 5350);
PAINT GREEN (-650 5350);
DISPLAY INVISIBLE (-650 5350);
FORCEPROP 2 LAST PATH I80
J 0
(-225 5500);
DISPLAY 0.680851 (-225 5500);
DISPLAY INVISIBLE (-225 5500);
FORCEADD OFFPAGE..1
R 2
(-500 5600);
FORCEPROP 2 LAST $XR1 310 
J 0
(-224 5600);
DISPLAY 0.638298 (-224 5600);
PAINT MONO (-224 5600);
FORCEPROP 2 LAST $XR0 81 
J 0
(-314 5600);
DISPLAY 0.638298 (-314 5600);
PAINT MONO (-314 5600);
FORCEPROP 2 LAST CDS_LIB standard
J 0
(-500 5600);
DISPLAY INVISIBLE (-500 5600);
FORCEPROP 1 LAST OFFPAGE TRUE
J 2
(-825 5475);
DISPLAY 0.872340 (-825 5475);
PAINT GREEN (-825 5475);
DISPLAY INVISIBLE (-825 5475);
FORCEPROP 1 LAST COMMENT_BODY TRUE
J 2
(-625 5500);
DISPLAY 0.872340 (-625 5500);
PAINT GREEN (-625 5500);
DISPLAY INVISIBLE (-625 5500);
FORCEPROP 2 LAST PATH I81
J 0
(-200 5650);
DISPLAY 0.680851 (-200 5650);
DISPLAY INVISIBLE (-200 5650);
FORCEADD P1V0..1
(-1475 6300);
FORCEPROP 3 LASTPIN (-1475 6250) SIG_NAME P1V8_CPU0_RT_1D\g
J 0
(-1465 6260);
DISPLAY 0.659574 (-1465 6260);
PAINT MONO (-1465 6260);
DISPLAY INVISIBLE (-1465 6260);
FORCEPROP 1 LAST HDL_POWER P1V8_CPU0_RT_1D
J 1
(-1475 6350);
DISPLAY 0.489362 (-1475 6350);
PAINT SKYBLUE (-1475 6350);
FORCEPROP 2 LAST CDS_LIB pure_quanta_power
J 0
(-1475 6300);
DISPLAY INVISIBLE (-1475 6300);
FORCEPROP 1 LAST PATH I82
J 0
(-1425 6325);
DISPLAY 0.872340 (-1425 6325);
PAINT AQUA (-1425 6325);
DISPLAY INVISIBLE (-1425 6325);
FORCEADD PT5161LRS..3
(-4375 2350);
FORCEPROP 1 LAST LOCATION U6013
J 0
(-4875 3975);
DISPLAY 0.723404 (-4875 3975);
FORCEPROP 0 LAST $SEC 3
J 0
(-4875 4125);
DISPLAY 0.680851 (-4875 4125);
PAINT MONO (-4875 4125);
DISPLAY INVISIBLE (-4875 4125);
FORCEPROP 0 LAST CDS_SEC 3
J 0
(-4875 4125);
DISPLAY 0.680851 (-4875 4125);
DISPLAY INVISIBLE (-4875 4125);
FORCEPROP 0 LASTPIN (-3775 2300) $PN G35
J 0
(-3765 2310);
DISPLAY 0.680851 (-3765 2310);
PAINT MONO (-3765 2310);
FORCEPROP 0 LASTPIN (-5025 1650) $PN FF5
J 2
(-5035 1660);
DISPLAY 0.680851 (-5035 1660);
PAINT MONO (-5035 1660);
FORCEPROP 0 LASTPIN (-5025 1550) $PN FJ3
J 2
(-5035 1560);
DISPLAY 0.680851 (-5035 1560);
PAINT MONO (-5035 1560);
FORCEPROP 0 LASTPIN (-5025 3550) $PN FJ6
J 2
(-5035 3560);
DISPLAY 0.680851 (-5035 3560);
PAINT MONO (-5035 3560);
FORCEPROP 0 LASTPIN (-5025 3450) $PN FJ23
J 2
(-5035 3460);
DISPLAY 0.680851 (-5035 3460);
PAINT MONO (-5035 3460);
FORCEPROP 0 LASTPIN (-5025 3350) $PN FJ25
J 2
(-5035 3360);
DISPLAY 0.680851 (-5035 3360);
PAINT MONO (-5035 3360);
FORCEPROP 0 LASTPIN (-5025 3250) $PN FJ28
J 2
(-5035 3260);
DISPLAY 0.680851 (-5035 3260);
PAINT MONO (-5035 3260);
FORCEPROP 0 LASTPIN (-3775 1900) $PN FJ31
J 0
(-3765 1910);
DISPLAY 0.680851 (-3765 1910);
PAINT MONO (-3765 1910);
FORCEPROP 0 LASTPIN (-3775 3650) $PN B3
J 0
(-3765 3660);
DISPLAY 0.680851 (-3765 3660);
PAINT MONO (-3765 3660);
FORCEPROP 0 LASTPIN (-3775 3350) $PN B6
J 0
(-3765 3360);
DISPLAY 0.680851 (-3765 3360);
PAINT MONO (-3765 3360);
FORCEPROP 0 LASTPIN (-3775 3550) $PN B9
J 0
(-3765 3560);
DISPLAY 0.680851 (-3765 3560);
PAINT MONO (-3765 3560);
FORCEPROP 0 LASTPIN (-3775 3100) $PN FF8
J 0
(-3765 3110);
DISPLAY 0.680851 (-3765 3110);
PAINT MONO (-3765 3110);
FORCEPROP 0 LASTPIN (-3775 3450) $PN B12
J 0
(-3765 3460);
DISPLAY 0.680851 (-3765 3460);
PAINT MONO (-3765 3460);
FORCEPROP 0 LASTPIN (-3775 3250) $PN E8
J 0
(-3765 3260);
DISPLAY 0.680851 (-3765 3260);
PAINT MONO (-3765 3260);
FORCEPROP 0 LASTPIN (-3775 2800) $PN FJ9
J 0
(-3765 2810);
DISPLAY 0.680851 (-3765 2810);
PAINT MONO (-3765 2810);
FORCEPROP 0 LASTPIN (-3775 2200) $PN F2
J 0
(-3765 2210);
DISPLAY 0.680851 (-3765 2210);
PAINT MONO (-3765 2210);
FORCEPROP 0 LASTPIN (-3775 1050) $PN E18
J 0
(-3765 1060);
DISPLAY 0.680851 (-3765 1060);
PAINT MONO (-3765 1060);
FORCEPROP 0 LASTPIN (-3775 1200) $PN B16
J 0
(-3765 1210);
DISPLAY 0.680851 (-3765 1210);
PAINT MONO (-3765 1210);
FORCEPROP 0 LASTPIN (-5025 1050) $PN FF18
J 2
(-5035 1060);
DISPLAY 0.680851 (-5035 1060);
PAINT MONO (-5035 1060);
FORCEPROP 0 LASTPIN (-5025 1200) $PN FJ16
J 2
(-5035 1210);
DISPLAY 0.680851 (-5035 1210);
PAINT MONO (-5035 1210);
FORCEPROP 0 LASTPIN (-3775 2100) $PN FF11
J 0
(-3765 2110);
DISPLAY 0.680851 (-3765 2110);
PAINT MONO (-3765 2110);
FORCEPROP 0 LASTPIN (-3775 2700) $PN E11
J 0
(-3765 2710);
DISPLAY 0.680851 (-3765 2710);
PAINT MONO (-3765 2710);
FORCEPROP 0 LASTPIN (-3775 2600) $PN FF33
J 0
(-3765 2610);
DISPLAY 0.680851 (-3765 2610);
PAINT MONO (-3765 2610);
FORCEPROP 0 LASTPIN (-5025 2650) $PN F34
J 2
(-5035 2660);
DISPLAY 0.680851 (-5035 2660);
PAINT MONO (-5035 2660);
FORCEPROP 0 LASTPIN (-5025 2550) $PN B23
J 2
(-5035 2560);
DISPLAY 0.680851 (-5035 2560);
PAINT MONO (-5035 2560);
FORCEPROP 0 LASTPIN (-5025 2450) $PN B25
J 2
(-5035 2460);
DISPLAY 0.680851 (-5035 2460);
PAINT MONO (-5035 2460);
FORCEPROP 0 LASTPIN (-5025 2900) $PN B31
J 2
(-5035 2910);
DISPLAY 0.680851 (-5035 2910);
PAINT MONO (-5035 2910);
FORCEPROP 0 LASTPIN (-5025 2800) $PN B28
J 2
(-5035 2810);
DISPLAY 0.680851 (-5035 2810);
PAINT MONO (-5035 2810);
FORCEPROP 0 LASTPIN (-3775 1700) $PN E30
J 0
(-3765 1710);
DISPLAY 0.680851 (-3765 1710);
PAINT MONO (-3765 1710);
FORCEPROP 0 LASTPIN (-5025 2150) $PN FF24
J 2
(-5035 2160);
DISPLAY 0.680851 (-5035 2160);
PAINT MONO (-5035 2160);
FORCEPROP 0 LASTPIN (-5025 2050) $PN FF27
J 2
(-5035 2060);
DISPLAY 0.680851 (-5035 2060);
PAINT MONO (-5035 2060);
FORCEPROP 0 LASTPIN (-5025 1950) $PN FF30
J 2
(-5035 1960);
DISPLAY 0.680851 (-5035 1960);
PAINT MONO (-5035 1960);
FORCEPROP 2 LAST PART_TYPE SMLF
J 0
(-4875 4075);
DISPLAY 0.680851 (-4875 4075);
FORCEPROP 1 LAST MATERIAL IC
J 0
(-4875 3825);
DISPLAY 0.723404 (-4875 3825);
PAINT GREEN (-4875 3825);
FORCEPROP 2 LAST VALUE PT5161LRS
J 0
(-4875 4025);
DISPLAY 0.680851 (-4875 4025);
FORCEPROP 1 LAST NEEDS_NO_SIZE TRUE
J 0
(-4375 2350);
DISPLAY 0.723404 (-4375 2350);
PAINT GREEN (-4375 2350);
DISPLAY INVISIBLE (-4375 2350);
FORCEPROP 1 LAST CDS_LMAN_SYM_OUTLINE -500,1450,450,-1400
J 0
(-4375 2350);
DISPLAY 0.468085 (-4375 2350);
PAINT GREEN (-4375 2350);
DISPLAY INVISIBLE (-4375 2350);
FORCEPROP 2 LAST CDS_LIB pure_quanta
J 0
(-4375 2350);
DISPLAY INVISIBLE (-4375 2350);
FORCEPROP 1 LAST PATH I83
J 0
(-4375 2350);
DISPLAY 0.723404 (-4375 2350);
PAINT GREEN (-4375 2350);
DISPLAY INVISIBLE (-4375 2350);
FORCEPROP 1 LAST PART_NUMBER AJ051610U03
J 0
(-4875 3900);
DISPLAY 0.723404 (-4875 3900);
PAINT GREEN (-4875 3900);
DISPLAY INVISIBLE (-4875 3900);
FORCEADD Q_RES..1
(-2700 3250);
FORCEPROP 1 LAST LOCATION R1408
J 0
(-2825 3250);
DISPLAY 0.787234 (-2825 3250);
PAINT WHITE (-2825 3250);
FORCEPROP 0 LAST $SEC 1
J 0
(-2325 3300);
DISPLAY 0.680851 (-2325 3300);
PAINT MONO (-2325 3300);
DISPLAY INVISIBLE (-2325 3300);
FORCEPROP 0 LAST CDS_SEC 1
J 0
(-2325 3300);
DISPLAY 0.680851 (-2325 3300);
DISPLAY INVISIBLE (-2325 3300);
FORCEPROP 1 LASTPIN (-2800 3250) $PN 1
J 0
(-2788 3262);
DISPLAY 0.787234 (-2788 3262);
PAINT MONO (-2788 3262);
FORCEPROP 1 LASTPIN (-2600 3250) $PN 2
J 0
(-2638 3262);
DISPLAY 0.787234 (-2638 3262);
PAINT MONO (-2638 3262);
FORCEPROP 1 LAST MATERIAL CHIP
J 0
(-2475 3250);
DISPLAY 0.638298 (-2475 3250);
FORCEPROP 1 LAST VALUE 1K
J 2
(-2500 3250);
DISPLAY 0.638298 (-2500 3250);
FORCEPROP 1 LAST PACK_TYPE 0201LF
J 0
(-2325 3250);
DISPLAY 0.638298 (-2325 3250);
FORCEPROP 1 LAST TOLERANCE 1%
J 0
(-2700 3150);
DISPLAY 0.638298 (-2700 3150);
DISPLAY INVISIBLE (-2700 3150);
FORCEPROP 1 LAST WATTAGE 1/20W
J 2
(-2725 3100);
DISPLAY 0.638298 (-2725 3100);
DISPLAY INVISIBLE (-2725 3100);
FORCEPROP 2 LAST CDS_LIB pure_quanta
J 0
(-2700 3250);
DISPLAY INVISIBLE (-2700 3250);
FORCEPROP 1 LAST PATH I85
J 0
(-2750 3400);
DISPLAY 0.978723 (-2750 3400);
PAINT WHITE (-2750 3400);
DISPLAY INVISIBLE (-2750 3400);
FORCEPROP 1 LAST PART_NUMBER CS21001FE07
J 0
(-2750 3350);
DISPLAY 0.978723 (-2750 3350);
DISPLAY INVISIBLE (-2750 3350);
FORCEADD Q_RES..2
(-8325 5050);
FORCEPROP 1 LAST LOCATION R1115
J 0
(-8280 5175);
DISPLAY 0.787234 (-8280 5175);
FORCEPROP 0 LAST $SEC 1
J 0
(-8275 5225);
DISPLAY 0.680851 (-8275 5225);
PAINT MONO (-8275 5225);
DISPLAY INVISIBLE (-8275 5225);
FORCEPROP 0 LAST CDS_SEC 1
J 0
(-8275 5225);
DISPLAY 0.680851 (-8275 5225);
DISPLAY INVISIBLE (-8275 5225);
FORCEPROP 1 LASTPIN (-8325 5150) $PN 1
J 0
(-8320 5112);
DISPLAY 0.787234 (-8320 5112);
PAINT MONO (-8320 5112);
FORCEPROP 1 LASTPIN (-8325 4950) $PN 2
J 0
(-8320 4960);
DISPLAY 0.787234 (-8320 4960);
PAINT MONO (-8320 4960);
FORCEPROP 1 LAST MATERIAL CHIP
J 0
(-8285 4975);
DISPLAY 0.787234 (-8285 4975);
FORCEPROP 1 LAST WATTAGE 1/20W
J 0
(-8285 5025);
DISPLAY 0.787234 (-8285 5025);
FORCEPROP 1 LAST VALUE 4.7K
J 0
(-8280 5125);
DISPLAY 0.787234 (-8280 5125);
FORCEPROP 1 LAST TOLERANCE 5%
J 0
(-8280 5075);
DISPLAY 0.787234 (-8280 5075);
FORCEPROP 1 LAST PACK_TYPE 0201LF
J 0
(-8285 4875);
DISPLAY 0.787234 (-8285 4875);
FORCEPROP 2 LAST CDS_LIB pure_quanta
J 0
(-8325 5050);
DISPLAY INVISIBLE (-8325 5050);
FORCEPROP 1 LAST PATH I9
J 0
(-8275 5225);
DISPLAY 0.978723 (-8275 5225);
PAINT WHITE (-8275 5225);
DISPLAY INVISIBLE (-8275 5225);
FORCEPROP 1 LAST PART_NUMBER CS24701JE04
J 0
(-8285 4925);
DISPLAY 0.978723 (-8285 4925);
DISPLAY INVISIBLE (-8285 4925);
FORCEADD UNIVERSAL_GND..1
R 1
(-1950 3250);
FORCEPROP 3 LASTPIN (-2000 3250) SIG_NAME GND\g
J 0
(-1990 3260);
DISPLAY 0.659574 (-1990 3260);
PAINT MONO (-1990 3260);
DISPLAY INVISIBLE (-1990 3260);
FORCEPROP 2 LAST CDS_LIB pure_quanta_power
J 0
(-1950 3250);
DISPLAY INVISIBLE (-1950 3250);
FORCEPROP 1 LAST HDL_POWER GND
R 1
J 1
(-1875 3275);
DISPLAY 0.872340 (-1875 3275);
PAINT GREEN (-1875 3275);
DISPLAY INVISIBLE (-1875 3275);
FORCEPROP 1 LAST PATH I92
R 1
J 0
(-1950 3325);
DISPLAY 0.872340 (-1950 3325);
PAINT AQUA (-1950 3325);
DISPLAY INVISIBLE (-1950 3325);
FORCEADD OFFPAGE..1
R 2
(-2400 2700);
FORCEPROP 2 LAST $XR0 310 
J 0
(-2214 2700);
DISPLAY 0.638298 (-2214 2700);
PAINT MONO (-2214 2700);
FORCEPROP 2 LAST CDS_LIB standard
J 0
(-2400 2700);
DISPLAY INVISIBLE (-2400 2700);
FORCEPROP 1 LAST OFFPAGE TRUE
J 2
(-2725 2575);
DISPLAY 0.872340 (-2725 2575);
DISPLAY INVISIBLE (-2725 2575);
FORCEPROP 1 LAST COMMENT_BODY TRUE
J 2
(-2525 2600);
DISPLAY 0.872340 (-2525 2600);
PAINT GREEN (-2525 2600);
DISPLAY INVISIBLE (-2525 2600);
FORCEPROP 2 LAST PATH I94
J 0
(-2225 2775);
DISPLAY 0.680851 (-2225 2775);
DISPLAY INVISIBLE (-2225 2775);
FORCEADD GND..1
(-1325 2850);
FORCEPROP 3 LASTPIN (-1325 2900) SIG_NAME GND\g
J 0
(-1315 2910);
DISPLAY 0.659574 (-1315 2910);
PAINT MONO (-1315 2910);
DISPLAY INVISIBLE (-1315 2910);
FORCEPROP 2 LAST BOM_COST MEM
J 0
(-1425 2925);
DISPLAY 0.808511 (-1425 2925);
DISPLAY INVISIBLE (-1425 2925);
FORCEPROP 1 LAST SIZE 1B
J 0
(-1250 2800);
DISPLAY 0.851064 (-1250 2800);
PAINT GREEN (-1250 2800);
DISPLAY INVISIBLE (-1250 2800);
FORCEPROP 2 LAST CDS_LIB pure_quanta_power
J 0
(-1325 2850);
DISPLAY INVISIBLE (-1325 2850);
FORCEPROP 1 LAST HDL_POWER GND
J 0
(-1325 3000);
DISPLAY 0.851064 (-1325 3000);
PAINT GREEN (-1325 3000);
DISPLAY INVISIBLE (-1325 3000);
FORCEPROP 1 LAST PATH I95
J 0
(-1250 2850);
DISPLAY 0.872340 (-1250 2850);
PAINT AQUA (-1250 2850);
DISPLAY INVISIBLE (-1250 2850);
FORCEADD Q_RES..2
(-1325 3250);
FORCEPROP 1 LAST LOCATION R1414
J 0
(-1280 3375);
DISPLAY 0.787234 (-1280 3375);
PAINT WHITE (-1280 3375);
FORCEPROP 0 LAST $SEC 1
J 0
(-1275 3425);
DISPLAY 0.680851 (-1275 3425);
PAINT MONO (-1275 3425);
DISPLAY INVISIBLE (-1275 3425);
FORCEPROP 0 LAST CDS_SEC 1
J 0
(-1275 3425);
DISPLAY 0.680851 (-1275 3425);
DISPLAY INVISIBLE (-1275 3425);
FORCEPROP 1 LASTPIN (-1325 3350) $PN 1
J 0
(-1320 3312);
DISPLAY 0.787234 (-1320 3312);
PAINT MONO (-1320 3312);
FORCEPROP 1 LASTPIN (-1325 3150) $PN 2
J 0
(-1320 3160);
DISPLAY 0.787234 (-1320 3160);
PAINT MONO (-1320 3160);
FORCEPROP 1 LAST WATTAGE 1/20W
J 0
(-1285 3225);
DISPLAY 0.787234 (-1285 3225);
FORCEPROP 1 LAST VALUE 10K
J 0
(-1280 3325);
DISPLAY 0.787234 (-1280 3325);
FORCEPROP 1 LAST PACK_TYPE 0201LF
J 0
(-1285 3075);
DISPLAY 0.787234 (-1285 3075);
FORCEPROP 1 LAST TOLERANCE 1%
J 0
(-1280 3275);
DISPLAY 0.787234 (-1280 3275);
FORCEPROP 1 LAST MATERIAL CHIP
J 0
(-1285 3175);
DISPLAY 0.787234 (-1285 3175);
FORCEPROP 2 LAST CDS_LIB pure_quanta
J 0
(-1325 3250);
DISPLAY INVISIBLE (-1325 3250);
FORCEPROP 1 LAST PATH I96
J 0
(-1275 3425);
DISPLAY 0.978723 (-1275 3425);
PAINT WHITE (-1275 3425);
DISPLAY INVISIBLE (-1275 3425);
FORCEPROP 1 LAST PART_NUMBER CS31001FE17
J 0
(-1285 3125);
DISPLAY 0.510638 (-1285 3125);
DISPLAY INVISIBLE (-1285 3125);
FORCEADD Q_RES..2
(-1325 3775);
FORCEPROP 1 LAST LOCATION R1413
J 0
(-1280 3900);
DISPLAY 0.787234 (-1280 3900);
PAINT WHITE (-1280 3900);
FORCEPROP 0 LAST $SEC 1
J 0
(-1275 3950);
DISPLAY 0.680851 (-1275 3950);
PAINT MONO (-1275 3950);
DISPLAY INVISIBLE (-1275 3950);
FORCEPROP 0 LAST CDS_SEC 1
J 0
(-1275 3950);
DISPLAY 0.680851 (-1275 3950);
DISPLAY INVISIBLE (-1275 3950);
FORCEPROP 1 LASTPIN (-1325 3875) $PN 1
J 0
(-1320 3837);
DISPLAY 0.787234 (-1320 3837);
PAINT MONO (-1320 3837);
FORCEPROP 1 LASTPIN (-1325 3675) $PN 2
J 0
(-1320 3685);
DISPLAY 0.787234 (-1320 3685);
PAINT MONO (-1320 3685);
FORCEPROP 1 LAST PACK_TYPE 0201LF
J 0
(-1285 3600);
DISPLAY 0.787234 (-1285 3600);
FORCEPROP 1 LAST TOLERANCE 1%
J 0
(-1280 3800);
DISPLAY 0.787234 (-1280 3800);
FORCEPROP 1 LAST WATTAGE 1/20W
J 0
(-1285 3750);
DISPLAY 0.787234 (-1285 3750);
FORCEPROP 1 LAST MATERIAL EMPTY
J 0
(-1285 3700);
DISPLAY 0.787234 (-1285 3700);
PAINT RED (-1285 3700);
FORCEPROP 1 LAST VALUE 1K
J 0
(-1280 3850);
DISPLAY 0.787234 (-1280 3850);
FORCEPROP 2 LAST CDS_LIB pure_quanta
J 0
(-1325 3775);
DISPLAY INVISIBLE (-1325 3775);
FORCEPROP 1 LAST PATH I97
J 0
(-1275 3950);
DISPLAY 0.978723 (-1275 3950);
PAINT WHITE (-1275 3950);
DISPLAY INVISIBLE (-1275 3950);
FORCEPROP 1 LAST PART_NUMBER CS21001FE07
J 0
(-1285 3650);
DISPLAY 0.978723 (-1285 3650);
DISPLAY INVISIBLE (-1285 3650);
FORCEADD P1V0..1
(-1325 4175);
FORCEPROP 3 LASTPIN (-1325 4125) SIG_NAME P1V8_CPU0_RT_1D\g
J 0
(-1315 4135);
DISPLAY 0.659574 (-1315 4135);
PAINT MONO (-1315 4135);
DISPLAY INVISIBLE (-1315 4135);
FORCEPROP 1 LAST HDL_POWER P1V8_CPU0_RT_1D
J 1
(-1325 4225);
DISPLAY 0.489362 (-1325 4225);
PAINT SKYBLUE (-1325 4225);
FORCEPROP 2 LAST CDS_LIB pure_quanta_power
J 0
(-1325 4175);
DISPLAY INVISIBLE (-1325 4175);
FORCEPROP 1 LAST PATH I98
J 0
(-1275 4200);
DISPLAY 0.872340 (-1275 4200);
PAINT AQUA (-1275 4200);
DISPLAY INVISIBLE (-1275 4200);
FORCEADD OFFPAGE..1
R 2
(-475 3500);
FORCEPROP 2 LAST $XR0 310 
J 0
(-289 3500);
DISPLAY 0.638298 (-289 3500);
PAINT MONO (-289 3500);
FORCEPROP 2 LAST CDS_LIB standard
J 0
(-475 3500);
DISPLAY INVISIBLE (-475 3500);
FORCEPROP 1 LAST OFFPAGE TRUE
J 2
(-800 3375);
DISPLAY 0.872340 (-800 3375);
DISPLAY INVISIBLE (-800 3375);
FORCEPROP 1 LAST COMMENT_BODY TRUE
J 2
(-600 3400);
DISPLAY 0.872340 (-600 3400);
PAINT GREEN (-600 3400);
DISPLAY INVISIBLE (-600 3400);
FORCEPROP 2 LAST PATH I99
J 0
(-300 3575);
DISPLAY 0.680851 (-300 3575);
DISPLAY INVISIBLE (-300 3575);
FORCEADD QUANTA_TITLE_BLOCK_C..1
(0 0);
FORCEPROP 0 LAST CDS_CON_LAST_MODIFIED Thu Sep 14 16:12:57 2023
J 0
(-1885 15);
DISPLAY INVISIBLE (-1885 15);
FORCEPROP 1 LAST CUSTOM_TXT_CDS <CON_LAST_MODIFIED>
J 0
(-1885 15);
DISPLAY 0.978723 (-1885 15);
FORCEPROP 2 LAST CUSTOM_TXT_CDS <XR_PAGE_TITLE>
J 0
(-7890 5250);
DISPLAY 0.638298 (-7890 5250);
PAINT PINK (-7890 5250);
DISPLAY INVISIBLE (-7890 5250);
FORCEPROP 1 LAST CUSTOM_TXT_CDS <NAME_2>
J 0
(-3175 50);
FORCEPROP 1 LAST CUSTOM_TXT_CDS <NAME_1>
J 0
(-3175 175);
FORCEPROP 1 LAST CUSTOM_TXT_CDS <Q_NUMBER>
J 0
(-1403 103);
DISPLAY 1.212766 (-1403 103);
FORCEPROP 1 LAST CUSTOM_TXT_CDS <Q_PROJ>
J 0
(-2382 102);
DISPLAY 1.212766 (-2382 102);
FORCEPROP 1 LAST CUSTOM_TXT_CDS <Q_REV>
J 0
(-184 103);
DISPLAY 1.212766 (-184 103);
FORCEPROP 1 LAST CUSTOM_TXT_CDS <CON_PAGE_NUM> OF <CON_TOTAL_PAGES>
J 0
(-446 18);
DISPLAY 0.978723 (-446 18);
FORCEPROP 1 LAST Q_TITLE RETIMER_CPU0_P3(5)
J 0
(-9366 26);
DISPLAY 2.446809 (-9366 26);
PAINT GREEN (-9366 26);
FORCEPROP 2 LAST PAGE_BORDER TRUE
J 0
(-7890 5250);
DISPLAY 0.638298 (-7890 5250);
PAINT PINK (-7890 5250);
DISPLAY INVISIBLE (-7890 5250);
FORCEPROP 1 LAST CDS_LMAN_SYM_OUTLINE -9475,6775,100,-125
J 0
(0 0);
DISPLAY 0.468085 (0 0);
PAINT GREEN (0 0);
DISPLAY INVISIBLE (0 0);
FORCEPROP 2 LAST CDS_LIB pure_quanta
J 0
(0 0);
DISPLAY INVISIBLE (0 0);
FORCEPROP 2 LAST CDS_XR_PAGE_TITLE CR-310 : @T6G_MB_LIB.T6G(SCH_1):PAGE310
J 0
(-7890 5250);
DISPLAY 0.638298 (-7890 5250);
PAINT PINK (-7890 5250);
DISPLAY INVISIBLE (-7890 5250);
FORCEPROP 1 LAST Q_DEPT BU9
J 1
(-3763 49);
DISPLAY 1.957447 (-3763 49);
PAINT GREEN (-3763 49);
DISPLAY INVISIBLE (-3763 49);
FORCEPROP 1 LAST COMMENT_BODY TRUE
J 0
(12 -13);
DISPLAY 0.978723 (12 -13);
PAINT GREEN (12 -13);
DISPLAY INVISIBLE (12 -13);
FORCEADD DNS..1
(-1475 6075);
PAINT RED (-1475 6075);
FORCEPROP 2 LAST CDS_LIB mstr_misc
J 0
(-1475 6075);
DISPLAY INVISIBLE (-1475 6075);
FORCEPROP 1 LAST COMMENT_BODY TRUE
R 1
J 0
(-1400 5850);
DISPLAY 0.872340 (-1400 5850);
PAINT GREEN (-1400 5850);
DISPLAY INVISIBLE (-1400 5850);
FORCEADD DNS..1
(-2775 6000);
PAINT RED (-2775 6000);
FORCEPROP 2 LAST CDS_LIB mstr_misc
J 0
(-2775 6000);
DISPLAY INVISIBLE (-2775 6000);
FORCEPROP 1 LAST COMMENT_BODY TRUE
R 1
J 0
(-2700 5775);
DISPLAY 0.872340 (-2700 5775);
PAINT GREEN (-2700 5775);
DISPLAY INVISIBLE (-2700 5775);
FORCEADD DNS..1
(-3125 6025);
PAINT RED (-3125 6025);
FORCEPROP 2 LAST CDS_LIB mstr_misc
J 0
(-3125 6025);
DISPLAY INVISIBLE (-3125 6025);
FORCEPROP 1 LAST COMMENT_BODY TRUE
R 1
J 0
(-3050 5800);
DISPLAY 0.872340 (-3050 5800);
PAINT GREEN (-3050 5800);
DISPLAY INVISIBLE (-3050 5800);
FORCEADD DNS..1
(-3425 5200);
PAINT RED (-3425 5200);
FORCEPROP 2 LAST CDS_LIB mstr_misc
J 0
(-3425 5200);
DISPLAY INVISIBLE (-3425 5200);
FORCEPROP 1 LAST COMMENT_BODY TRUE
R 1
J 0
(-3350 4975);
DISPLAY 0.872340 (-3350 4975);
PAINT GREEN (-3350 4975);
DISPLAY INVISIBLE (-3350 4975);
FORCEADD DNS..1
(-4950 5500);
PAINT RED (-4950 5500);
FORCEPROP 2 LAST CDS_LIB mstr_misc
J 0
(-4950 5500);
DISPLAY INVISIBLE (-4950 5500);
FORCEPROP 1 LAST COMMENT_BODY TRUE
R 1
J 0
(-4875 5275);
DISPLAY 0.872340 (-4875 5275);
PAINT GREEN (-4875 5275);
DISPLAY INVISIBLE (-4875 5275);
FORCEADD DNS..1
(-7325 5975);
PAINT RED (-7325 5975);
FORCEPROP 2 LAST CDS_LIB mstr_misc
J 0
(-7325 5975);
DISPLAY INVISIBLE (-7325 5975);
FORCEPROP 1 LAST COMMENT_BODY TRUE
R 1
J 0
(-7250 5750);
DISPLAY 0.872340 (-7250 5750);
PAINT GREEN (-7250 5750);
DISPLAY INVISIBLE (-7250 5750);
FORCEADD DNS..1
(-7650 6025);
PAINT RED (-7650 6025);
FORCEPROP 2 LAST CDS_LIB mstr_misc
J 0
(-7650 6025);
DISPLAY INVISIBLE (-7650 6025);
FORCEPROP 1 LAST COMMENT_BODY TRUE
R 1
J 0
(-7575 5800);
DISPLAY 0.872340 (-7575 5800);
PAINT GREEN (-7575 5800);
DISPLAY INVISIBLE (-7575 5800);
FORCEADD DNS..1
(-7925 5975);
PAINT RED (-7925 5975);
FORCEPROP 2 LAST CDS_LIB mstr_misc
J 0
(-7925 5975);
DISPLAY INVISIBLE (-7925 5975);
FORCEPROP 1 LAST COMMENT_BODY TRUE
R 1
J 0
(-7850 5750);
DISPLAY 0.872340 (-7850 5750);
PAINT GREEN (-7850 5750);
DISPLAY INVISIBLE (-7850 5750);
FORCEADD DNS..1
(-6050 675);
PAINT RED (-6050 675);
FORCEPROP 2 LAST CDS_LIB mstr_misc
J 0
(-6050 675);
DISPLAY INVISIBLE (-6050 675);
FORCEPROP 1 LAST COMMENT_BODY TRUE
R 1
J 0
(-5975 450);
DISPLAY 0.872340 (-5975 450);
PAINT GREEN (-5975 450);
DISPLAY INVISIBLE (-5975 450);
FORCEADD DNS..1
(-6425 625);
PAINT RED (-6425 625);
FORCEPROP 2 LAST CDS_LIB mstr_misc
J 0
(-6425 625);
DISPLAY INVISIBLE (-6425 625);
FORCEPROP 1 LAST COMMENT_BODY TRUE
R 1
J 0
(-6350 400);
DISPLAY 0.872340 (-6350 400);
PAINT GREEN (-6350 400);
DISPLAY INVISIBLE (-6350 400);
FORCEADD DNS..1
(-8225 6000);
PAINT RED (-8225 6000);
FORCEPROP 2 LAST CDS_LIB mstr_misc
J 0
(-8225 6000);
DISPLAY INVISIBLE (-8225 6000);
FORCEPROP 1 LAST COMMENT_BODY TRUE
R 1
J 0
(-8150 5775);
DISPLAY 0.872340 (-8150 5775);
PAINT GREEN (-8150 5775);
DISPLAY INVISIBLE (-8150 5775);
FORCEADD DNS..1
(-8825 5975);
PAINT RED (-8825 5975);
FORCEPROP 2 LAST CDS_LIB mstr_misc
J 0
(-8825 5975);
DISPLAY INVISIBLE (-8825 5975);
FORCEPROP 1 LAST COMMENT_BODY TRUE
R 1
J 0
(-8750 5750);
DISPLAY 0.872340 (-8750 5750);
PAINT GREEN (-8750 5750);
DISPLAY INVISIBLE (-8750 5750);
FORCEADD DNS..1
(-8925 4100);
PAINT RED (-8925 4100);
FORCEPROP 2 LAST CDS_LIB mstr_misc
J 0
(-8925 4100);
DISPLAY INVISIBLE (-8925 4100);
FORCEPROP 1 LAST COMMENT_BODY TRUE
R 1
J 0
(-8850 3875);
DISPLAY 0.872340 (-8850 3875);
PAINT GREEN (-8850 3875);
DISPLAY INVISIBLE (-8850 3875);
FORCEADD DNS..1
(-1250 3775);
PAINT RED (-1250 3775);
FORCEPROP 2 LAST CDS_LIB mstr_misc
J 0
(-1250 3775);
DISPLAY INVISIBLE (-1250 3775);
FORCEPROP 1 LAST COMMENT_BODY TRUE
R 1
J 0
(-1175 3550);
DISPLAY 0.872340 (-1175 3550);
PAINT GREEN (-1175 3550);
DISPLAY INVISIBLE (-1175 3550);
FORCEADD DNS..1
(-925 1375);
PAINT RED (-925 1375);
FORCEPROP 2 LAST CDS_LIB mstr_misc
J 0
(-925 1375);
DISPLAY INVISIBLE (-925 1375);
FORCEPROP 1 LAST COMMENT_BODY TRUE
R 1
J 0
(-850 1150);
DISPLAY 0.872340 (-850 1150);
PAINT GREEN (-850 1150);
DISPLAY INVISIBLE (-850 1150);
FORCEADD DNS..1
(-1225 1425);
PAINT RED (-1225 1425);
FORCEPROP 2 LAST CDS_LIB mstr_misc
J 0
(-1225 1425);
DISPLAY INVISIBLE (-1225 1425);
FORCEPROP 1 LAST COMMENT_BODY TRUE
R 1
J 0
(-1150 1200);
DISPLAY 0.872340 (-1150 1200);
PAINT GREEN (-1150 1200);
DISPLAY INVISIBLE (-1150 1200);
FORCEADD DNS..1
(-350 1400);
PAINT RED (-350 1400);
FORCEPROP 2 LAST CDS_LIB mstr_misc
J 0
(-350 1400);
DISPLAY INVISIBLE (-350 1400);
FORCEPROP 1 LAST COMMENT_BODY TRUE
R 1
J 0
(-275 1175);
DISPLAY 0.872340 (-275 1175);
PAINT GREEN (-275 1175);
DISPLAY INVISIBLE (-275 1175);
FORCEADD DNS..1
(-625 1400);
PAINT RED (-625 1400);
FORCEPROP 2 LAST CDS_LIB mstr_misc
J 0
(-625 1400);
DISPLAY INVISIBLE (-625 1400);
FORCEPROP 1 LAST COMMENT_BODY TRUE
R 1
J 0
(-550 1175);
DISPLAY 0.872340 (-550 1175);
PAINT GREEN (-550 1175);
DISPLAY INVISIBLE (-550 1175);
WIRE 16 -1 (-2575 2300)(-2000 2300);
WIRE 16 -1 (-425 650)(-425 500);
WIRE 16 -1 (-6300 625)(-6300 450);
WIRE 16 -1 (-6150 625)(-6150 450);
WIRE 16 -1 (-8975 3350)(-8975 3225);
WIRE 16 -1 (-5025 5450)(-5025 5250);
WIRE 16 -1 (-5025 6175)(-5025 6350);
WIRE 16 -1 (-3775 1700)(-2675 1700);
WIRE 16 -1 (-8975 4225)(-8975 4400);
WIRE 16 -1 (-1475 5125)(-1475 4900);
WIRE 16 -1 (-1300 5125)(-1300 4925);
WIRE 16 -1 (-1475 6250)(-1475 6150);
WIRE 16 -1 (-2600 3250)(-2000 3250);
WIRE 16 -1 (-1325 3150)(-1325 2900);
WIRE 16 -1 (-1325 3875)(-1325 4125);
WIRE 16 -1 (-6425 1650)(-7725 1650);
FORCEPROP 2 LAST SIG_NAME SMB_RT_CPU0_P3_ROM_MUX_1D_SCL
J 0
(-7635 1660);
DISPLAY 0.680851 (-7635 1660);
WIRE 16 -1 (-5025 1650)(-6225 1650);
FORCEPROP 2 LAST SIG_NAME SMB_RT_CPU0_P3_ROM_MUX_1D_R_SCL
J 0
(-6185 1675);
DISPLAY 0.680851 (-6185 1675);
FORCEPROP 2 LASTPROP $XRERR UNIQUE?
J 0
(-6425 1675);
DISPLAY 0.638298 (-6425 1675);
PAINT MONO (-6425 1675);
DISPLAY INVISIBLE (-6425 1675);
WIRE 16 -1 (-6425 1550)(-7725 1550);
FORCEPROP 2 LAST SIG_NAME SMB_RT_CPU0_P3_ROM_MUX_1D_SDA
J 0
(-7660 1560);
DISPLAY 0.680851 (-7660 1560);
WIRE 16 -1 (-5025 1550)(-6225 1550);
FORCEPROP 2 LAST SIG_NAME SMB_RT_CPU0_P3_ROM_MUX_1D_R_SDA
J 0
(-6185 1575);
DISPLAY 0.680851 (-6185 1575);
FORCEPROP 2 LASTPROP $XRERR UNIQUE?
J 0
(-6425 1575);
DISPLAY 0.638298 (-6425 1575);
PAINT MONO (-6425 1575);
DISPLAY INVISIBLE (-6425 1575);
WIRE 16 -1 (-7850 3900)(-8975 3900);
FORCEPROP 2 LAST SIG_NAME RT_CPU0_P3_SCAN_MODE
J 0
(-8585 3910);
DISPLAY 0.680851 (-8585 3910);
WIRE 16 -1 (-8975 4025)(-8975 3900);
WIRE 16 -1 (-8975 3900)(-8975 3550);
WIRE 16 -1 (-3775 2200)(-2675 2200);
FORCEPROP 2 LAST SIG_NAME RST_RT_CPU0_P3_PERST_N
J 0
(-3610 2210);
DISPLAY 0.680851 (-3610 2210);
FORCEPROP 2 LASTPROP $XRERR UNIQUE?
J 0
(-3850 2210);
DISPLAY 0.638298 (-3850 2210);
PAINT MONO (-3850 2210);
DISPLAY INVISIBLE (-3850 2210);
WIRE 16 -1 (-3775 2100)(-2675 2100);
FORCEPROP 2 LAST SIG_NAME RST_RT_CPU0_P3_RESET_N
J 0
(-3585 2110);
DISPLAY 0.680851 (-3585 2110);
FORCEPROP 2 LASTPROP $XRERR UNIQUE?
J 0
(-3825 2110);
DISPLAY 0.638298 (-3825 2110);
PAINT MONO (-3825 2110);
DISPLAY INVISIBLE (-3825 2110);
WIRE 16 -1 (-7725 6300)(-7425 6300);
WIRE 16 -1 (-7725 6300)(-8025 6300);
WIRE 16 -1 (-7725 6300)(-7725 6075);
WIRE 16 -1 (-7425 6300)(-7425 6100);
WIRE 16 -1 (-8025 6300)(-8025 6050);
WIRE 16 -1 (-8025 6300)(-8325 6300);
WIRE 16 -1 (-8950 6300)(-8325 6300);
WIRE 16 -1 (-8325 6300)(-8325 6100);
WIRE 16 -1 (-8950 6350)(-8950 6300);
WIRE 16 -1 (-8950 6300)(-8950 6100);
WIRE 16 -1 (-1250 1475)(-1250 1625);
WIRE 16 -1 (-1250 1625)(-975 1625);
WIRE 16 -1 (-975 1625)(-700 1625);
WIRE 16 -1 (-975 1475)(-975 1625);
WIRE 16 -1 (-700 1625)(-425 1625);
WIRE 16 -1 (-700 1475)(-700 1625);
WIRE 16 -1 (-425 1625)(-425 1650);
WIRE 16 -1 (-425 1500)(-425 1625);
WIRE 16 -1 (-8950 4950)(-8950 4725);
WIRE 16 -1 (-8950 4725)(-8650 4725);
WIRE 16 -1 (-8650 4725)(-8325 4725);
WIRE 16 -1 (-8650 4950)(-8650 4725);
WIRE 16 -1 (-8025 4725)(-8325 4725);
WIRE 16 -1 (-8325 4950)(-8325 4725);
WIRE 16 -1 (-7725 4725)(-8025 4725);
WIRE 16 -1 (-8025 4925)(-8025 4725);
WIRE 16 -1 (-7725 4725)(-7425 4725);
WIRE 16 -1 (-7725 4925)(-7725 4725);
WIRE 16 -1 (-7425 4900)(-7425 4725);
WIRE 16 -1 (-7425 4725)(-7425 4600);
WIRE 16 -1 (-2825 5125)(-2825 4950);
WIRE 16 -1 (-2825 4950)(-3175 4950);
WIRE 16 -1 (-3175 5125)(-3175 4950);
WIRE 16 -1 (-3175 4950)(-3475 4950);
WIRE 16 -1 (-3475 5125)(-3475 4950);
WIRE 16 -1 (-3475 4950)(-3475 4850);
WIRE 16 -1 (-3175 6325)(-2825 6325);
WIRE 16 -1 (-3475 6325)(-3175 6325);
WIRE 16 -1 (-3175 6325)(-3175 6100);
WIRE 16 -1 (-2825 6325)(-2825 6075);
WIRE 16 -1 (-3475 6100)(-3475 6325);
WIRE 16 -1 (-3475 6325)(-3475 6375);
WIRE 16 -1 (-3775 2300)(-2775 2300);
FORCEPROP 2 LAST SIG_NAME CLKREQ_RT_CPU0_P3_N
J 0
(-3510 2310);
DISPLAY 0.680851 (-3510 2310);
PAINT WHITE (-3510 2310);
FORCEPROP 2 LASTPROP $XRERR UNIQUE?
J 0
(-3750 2310);
DISPLAY 0.638298 (-3750 2310);
PAINT MONO (-3750 2310);
DISPLAY INVISIBLE (-3750 2310);
WIRE 16 -1 (-700 1275)(-700 1075);
WIRE 16 -1 (-2350 1075)(-700 1075);
FORCEPROP 2 LAST SIG_NAME JTAG_TDO_RT_CPU0_P3
J 0
(-2160 1085);
DISPLAY 0.680851 (-2160 1085);
PAINT WHITE (-2160 1085);
WIRE 16 -1 (-975 1275)(-975 1025);
WIRE 16 -1 (-2350 1025)(-975 1025);
FORCEPROP 2 LAST SIG_NAME JTAG_TMS_RT_CPU0_P3
J 0
(-2160 1035);
DISPLAY 0.680851 (-2160 1035);
PAINT WHITE (-2160 1035);
WIRE 16 -1 (-1250 1275)(-1250 975);
WIRE 16 -1 (-2350 975)(-1250 975);
FORCEPROP 2 LAST SIG_NAME JTAG_TDI_RT_CPU0_P3
J 0
(-2185 985);
DISPLAY 0.680851 (-2185 985);
PAINT WHITE (-2185 985);
WIRE 16 -1 (-425 1300)(-425 1125);
WIRE 16 -1 (-425 1125)(-425 850);
WIRE 16 -1 (-2350 1125)(-425 1125);
FORCEPROP 2 LAST SIG_NAME JTAG_TCK_RT_CPU0_P3
J 0
(-2185 1135);
DISPLAY 0.680851 (-2185 1135);
PAINT WHITE (-2185 1135);
WIRE 16 -1 (-3775 3650)(-2775 3650);
FORCEPROP 2 LAST SIG_NAME JTAG_TCK_RT_CPU0_P3
J 0
(-3610 3660);
DISPLAY 0.680851 (-3610 3660);
PAINT WHITE (-3610 3660);
WIRE 16 -1 (-3775 3250)(-2800 3250);
FORCEPROP 2 LAST SIG_NAME JTAG_TRST_RT_CPU0_P3_N
J 0
(-3610 3260);
DISPLAY 0.680851 (-3610 3260);
PAINT WHITE (-3610 3260);
FORCEPROP 2 LASTPROP $XRERR UNIQUE?
J 0
(-3850 3260);
DISPLAY 0.638298 (-3850 3260);
PAINT MONO (-3850 3260);
DISPLAY INVISIBLE (-3850 3260);
WIRE 16 -1 (-3775 3450)(-2775 3450);
FORCEPROP 2 LAST SIG_NAME JTAG_TMS_RT_CPU0_P3
J 0
(-3585 3460);
DISPLAY 0.680851 (-3585 3460);
PAINT WHITE (-3585 3460);
WIRE 16 -1 (-5025 3350)(-5975 3350);
FORCEPROP 2 LAST SIG_NAME GPIO2_RT_CPU0_P3
J 0
(-5835 3360);
DISPLAY 0.680851 (-5835 3360);
WIRE 16 -1 (-1325 3350)(-1325 3500);
WIRE 16 -1 (-525 3500)(-1325 3500);
FORCEPROP 2 LAST SIG_NAME RXDET_BYP_RT_CPU0_P3
J 0
(-1210 3510);
DISPLAY 0.680851 (-1210 3510);
PAINT WHITE (-1210 3510);
WIRE 16 -1 (-1325 3500)(-1325 3675);
WIRE 16 -1 (-1475 5325)(-1475 5600);
WIRE 16 -1 (-550 5600)(-1475 5600);
FORCEPROP 2 LAST SIG_NAME RST_RT_CPU0_P3_RESET_R_N
J 0
(-1435 5635);
DISPLAY 0.680851 (-1435 5635);
WIRE 16 -1 (-1475 5950)(-1475 5600);
WIRE 16 -1 (-1300 5450)(-575 5450);
WIRE 16 -1 (-1300 5325)(-1300 5450);
FORCEPROP 2 LAST SIG_NAME RST_RT_CPU0_P3_PERST_R_N
J 0
(-1335 5485);
DISPLAY 0.680851 (-1335 5485);
WIRE 16 -1 (-3175 5325)(-3175 5575);
WIRE 16 -1 (-1975 5575)(-3175 5575);
FORCEPROP 2 LAST SIG_NAME RT_CPU0_P3_ADDR2
J 0
(-2760 5585);
DISPLAY 0.680851 (-2760 5585);
WIRE 16 -1 (-3175 5575)(-3175 5900);
WIRE 16 -1 (-5025 5650)(-5025 5800);
WIRE 16 -1 (-4200 5800)(-5025 5800);
FORCEPROP 2 LAST SIG_NAME MODE_RT_CPU0_P3
J 0
(-4810 5810);
DISPLAY 0.680851 (-4810 5810);
WIRE 16 -1 (-5025 5975)(-5025 5800);
WIRE 16 -1 (-7725 5125)(-7725 5475);
WIRE 16 -1 (-6425 5475)(-7725 5475);
FORCEPROP 2 LAST SIG_NAME TEST2_RT_CPU0_P3
J 0
(-6985 5485);
DISPLAY 0.680851 (-6985 5485);
WIRE 16 -1 (-7725 5875)(-7725 5475);
WIRE 16 -1 (-5025 3250)(-5975 3250);
FORCEPROP 2 LAST SIG_NAME GPIO3_RT_CPU0_P3
J 0
(-5835 3260);
DISPLAY 0.680851 (-5835 3260);
WIRE 16 -1 (-6425 5400)(-7425 5400);
FORCEPROP 2 LAST SIG_NAME JTAG_TEST_MODE_RT_CPU0_P3
J 0
(-7235 5410);
DISPLAY 0.680851 (-7235 5410);
WIRE 16 -1 (-7425 5900)(-7425 5400);
WIRE 16 -1 (-7425 5400)(-7425 5100);
WIRE 16 -1 (-5025 1950)(-6100 1950);
FORCEPROP 2 LAST SIG_NAME TEST2_RT_CPU0_P3
J 0
(-5785 1960);
DISPLAY 0.680851 (-5785 1960);
WIRE 16 -1 (-6425 5625)(-8650 5625);
FORCEPROP 2 LAST SIG_NAME GPIO3_RT_CPU0_P3
J 0
(-7010 5635);
DISPLAY 0.680851 (-7010 5635);
WIRE 16 -1 (-8650 5625)(-8650 5150);
WIRE 16 -1 (-8950 5150)(-8950 5700);
WIRE 16 -1 (-6425 5700)(-8950 5700);
FORCEPROP 2 LAST SIG_NAME GPIO2_RT_CPU0_P3
J 0
(-6985 5710);
DISPLAY 0.680851 (-6985 5710);
WIRE 16 -1 (-8950 5900)(-8950 5700);
WIRE 16 -1 (-8325 5150)(-8325 5575);
WIRE 16 -1 (-6425 5575)(-8325 5575);
FORCEPROP 2 LAST SIG_NAME TEST0_RT_CPU0_P3
J 0
(-6985 5585);
DISPLAY 0.680851 (-6985 5585);
WIRE 16 -1 (-8325 5900)(-8325 5575);
WIRE 16 -1 (-8025 5125)(-8025 5525);
WIRE 16 -1 (-6425 5525)(-8025 5525);
FORCEPROP 2 LAST SIG_NAME TEST1_RT_CPU0_P3
J 0
(-6985 5535);
DISPLAY 0.680851 (-6985 5535);
WIRE 16 -1 (-8025 5850)(-8025 5525);
WIRE 16 -1 (-5025 2800)(-6250 2800);
FORCEPROP 2 LAST SIG_NAME SMB_RT_CPU0_P3_R2_SDA
J 0
(-6010 2810);
DISPLAY 0.680851 (-6010 2810);
FORCEPROP 2 LASTPROP $XRERR UNIQUE?
J 0
(-6250 2810);
DISPLAY 0.638298 (-6250 2810);
PAINT MONO (-6250 2810);
DISPLAY INVISIBLE (-6250 2810);
WIRE 16 -1 (-5025 2900)(-6250 2900);
FORCEPROP 2 LAST SIG_NAME SMB_RT_CPU0_P3_R2_SCL
J 0
(-6010 2910);
DISPLAY 0.680851 (-6010 2910);
FORCEPROP 2 LASTPROP $XRERR UNIQUE?
J 0
(-6250 2910);
DISPLAY 0.638298 (-6250 2910);
PAINT MONO (-6250 2910);
DISPLAY INVISIBLE (-6250 2910);
WIRE 16 -1 (-6450 2900)(-7600 2900);
FORCEPROP 2 LAST SIG_NAME SMB_RT_CPU0_P3_R_SCL
J 0
(-7435 2910);
DISPLAY 0.680851 (-7435 2910);
WIRE 16 -1 (-6450 2800)(-7600 2800);
FORCEPROP 2 LAST SIG_NAME SMB_RT_CPU0_P3_R_SDA
J 0
(-7435 2810);
DISPLAY 0.680851 (-7435 2810);
WIRE 16 -1 (-5025 2550)(-5925 2550);
FORCEPROP 2 LAST SIG_NAME RT_CPU0_P3_ADDR2
J 0
(-5785 2560);
DISPLAY 0.680851 (-5785 2560);
WIRE 16 -1 (-5025 2650)(-5925 2650);
FORCEPROP 2 LAST SIG_NAME RT_CPU0_P3_ADDR1
J 0
(-5785 2660);
DISPLAY 0.680851 (-5785 2660);
WIRE 16 -1 (-1975 5675)(-3475 5675);
FORCEPROP 2 LAST SIG_NAME RT_CPU0_P3_ADDR3
J 0
(-2760 5710);
DISPLAY 0.680851 (-2760 5710);
WIRE 16 -1 (-3475 5900)(-3475 5675);
WIRE 16 -1 (-3475 5675)(-3475 5325);
WIRE 16 -1 (-2825 5325)(-2825 5475);
WIRE 16 -1 (-1975 5475)(-2825 5475);
FORCEPROP 2 LAST SIG_NAME RT_CPU0_P3_ADDR1
J 0
(-2760 5485);
DISPLAY 0.680851 (-2760 5485);
WIRE 16 -1 (-2825 5475)(-2825 5875);
WIRE 16 -1 (-5025 2050)(-6100 2050);
FORCEPROP 2 LAST SIG_NAME TEST1_RT_CPU0_P3
J 0
(-5785 2060);
DISPLAY 0.680851 (-5785 2060);
WIRE 16 -1 (-5025 2150)(-6100 2150);
FORCEPROP 2 LAST SIG_NAME TEST0_RT_CPU0_P3
J 0
(-5785 2160);
DISPLAY 0.680851 (-5785 2160);
WIRE 16 -1 (-5025 2450)(-5925 2450);
FORCEPROP 2 LAST SIG_NAME RT_CPU0_P3_ADDR3
J 0
(-5785 2460);
DISPLAY 0.680851 (-5785 2460);
WIRE 16 -1 (-6700 1050)(-8000 1050);
FORCEPROP 2 LAST SIG_NAME CLK_100M_RETIMER_CPU0_P3_R_DN
J 0
(-7960 1060);
DISPLAY 0.680851 (-7960 1060);
WIRE 16 -1 (-5025 1200)(-6150 1200);
FORCEPROP 2 LAST SIG_NAME CLK_100M_RETIMER_CPU0_P3_DP
J 0
(-6060 1210);
DISPLAY 0.680851 (-6060 1210);
FORCEPROP 2 LASTPROP $XRERR UNIQUE?
J 0
(-6300 1210);
DISPLAY 0.638298 (-6300 1210);
PAINT MONO (-6300 1210);
DISPLAY INVISIBLE (-6300 1210);
WIRE 16 -1 (-6150 1200)(-6500 1200);
WIRE 16 -1 (-6150 1200)(-6150 825);
WIRE 16 -1 (-6700 1200)(-8000 1200);
FORCEPROP 2 LAST SIG_NAME CLK_100M_RETIMER_CPU0_P3_R_DP
J 0
(-7935 1210);
DISPLAY 0.680851 (-7935 1210);
WIRE 16 -1 (-5025 1050)(-6300 1050);
FORCEPROP 2 LAST SIG_NAME CLK_100M_RETIMER_CPU0_P3_DN
J 0
(-6060 1060);
DISPLAY 0.680851 (-6060 1060);
FORCEPROP 2 LASTPROP $XRERR UNIQUE?
J 0
(-6300 1060);
DISPLAY 0.638298 (-6300 1060);
PAINT MONO (-6300 1060);
DISPLAY INVISIBLE (-6300 1060);
WIRE 16 -1 (-6300 1050)(-6500 1050);
WIRE 16 -1 (-6300 1050)(-6300 825);
WIRE 16 -1 (-3775 3550)(-2775 3550);
FORCEPROP 2 LAST SIG_NAME JTAG_TDO_RT_CPU0_P3
J 0
(-3585 3560);
DISPLAY 0.680851 (-3585 3560);
PAINT WHITE (-3585 3560);
WIRE 16 -1 (-3775 3350)(-2800 3350);
FORCEPROP 2 LAST SIG_NAME JTAG_TDI_RT_CPU0_P3
J 0
(-3610 3360);
DISPLAY 0.680851 (-3610 3360);
PAINT WHITE (-3610 3360);
WIRE 16 -1 (-3775 3100)(-2525 3100);
FORCEPROP 2 LAST SIG_NAME JTAG_TEST_MODE_RT_CPU0_P3
J 0
(-3585 3110);
DISPLAY 0.680851 (-3585 3110);
WIRE 16 -1 (-3775 2800)(-2450 2800);
FORCEPROP 2 LAST SIG_NAME MODE_RT_CPU0_P3
J 0
(-3460 2810);
DISPLAY 0.680851 (-3460 2810);
WIRE 16 -1 (-3775 2700)(-2450 2700);
FORCEPROP 2 LAST SIG_NAME RXDET_BYP_RT_CPU0_P3
J 0
(-3460 2710);
DISPLAY 0.680851 (-3460 2710);
PAINT WHITE (-3460 2710);
WIRE 16 -1 (-3775 2600)(-2425 2600);
FORCEPROP 2 LAST SIG_NAME RT_CPU0_P3_SCAN_MODE
J 0
(-3485 2610);
DISPLAY 0.680851 (-3485 2610);
WIRE 16 -1 (-2475 2200)(-1100 2200);
FORCEPROP 2 LAST SIG_NAME RST_RT_CPU0_P3_PERST_R_N
J 0
(-1935 2210);
DISPLAY 0.680851 (-1935 2210);
WIRE 16 -1 (-2475 2100)(-1100 2100);
FORCEPROP 2 LAST SIG_NAME RST_RT_CPU0_P3_RESET_R_N
J 0
(-1960 2110);
DISPLAY 0.680851 (-1960 2110);
DOT 1 (-8975 3900);
DOT 1 (-1325 3500);
DOT 1 (-6300 1050);
DOT 1 (-1475 5600);
DOT 1 (-3175 6325);
DOT 1 (-3475 6325);
DOT 1 (-2825 5475);
DOT 1 (-3175 5575);
DOT 1 (-3475 5675);
DOT 1 (-3175 4950);
DOT 1 (-3475 4950);
DOT 1 (-5025 5800);
DOT 1 (-8025 6300);
DOT 1 (-7725 6300);
DOT 1 (-7425 5400);
DOT 1 (-7725 5475);
DOT 1 (-8025 5525);
DOT 1 (-7425 4725);
DOT 1 (-7725 4725);
DOT 1 (-8025 4725);
DOT 1 (-6150 1200);
DOT 1 (-8325 6300);
DOT 1 (-8950 6300);
DOT 1 (-8325 5575);
DOT 1 (-8950 5700);
DOT 1 (-8325 4725);
DOT 1 (-8650 4725);
DOT 1 (-975 1625);
DOT 1 (-700 1625);
DOT 1 (-425 1125);
DOT 1 (-425 1625);
FORCENOTE
CPU1 P0 RT ADDR: 0X48 (8-BIT) / 0X24 (7-BIT)
(-4275 4625) 0;
DISPLAY LEFT (-4275 4625);
DISPLAY 1.595745 (-4275 4625);
QUIT
